FILE_TYPE = MACRO_DRAWING;
SET COLOR_WIRE YELLOW;
SET COLOR_PROP MONO;
SET COLOR_DOT WHITE;
SET COLOR_ARC YELLOW;
SET COLOR_BODY GREEN;
SET COLOR_NOTE MONO;
SET PROP_DISPLAY VALUE;
SET PAGE_NUMBER P195;
FORCEADD CAPP..1
(-7700 775);
FORCEPROP 1 LAST MATERIAL TANT
J 0
(-7650 675);
DISPLAY 0.617021 (-7650 675);
PAINT SKYBLUE (-7650 675);
FORCEPROP 1 LAST VOLTAGE 16V
J 0
(-7650 725);
DISPLAY 0.617021 (-7650 725);
PAINT SKYBLUE (-7650 725);
FORCEPROP 1 LAST PACK_TYPE 3018
J 0
(-7650 625);
DISPLAY 0.617021 (-7650 625);
PAINT SKYBLUE (-7650 625);
FORCEPROP 1 LAST TOLERANCE 20%
J 0
(-7650 775);
DISPLAY 0.617021 (-7650 775);
PAINT SKYBLUE (-7650 775);
FORCEPROP 1 LAST VALUE 68UF
J 0
(-7650 825);
DISPLAY 0.617021 (-7650 825);
PAINT SKYBLUE (-7650 825);
FORCEPROP 1 LAST LOCATION C3B6
J 0
(-7650 875);
DISPLAY 0.617021 (-7650 875);
PAINT AQUA (-7650 875);
FORCEPROP 1 LAST PART_NUMBER 724613-112
J 0
(-7650 575);
DISPLAY 0.617021 (-7650 575);
PAINT BLUE (-7650 575);
FORCEPROP 1 LASTPIN (-7700 675) $PN 2
J 0
(-7690 660);
DISPLAY 0.787234 (-7690 660);
PAINT ORANGE (-7690 660);
DISPLAY INVISIBLE (-7690 660);
FORCEPROP 1 LASTPIN (-7700 875) $PN 1
J 0
(-7690 860);
DISPLAY 0.787234 (-7690 860);
PAINT ORANGE (-7690 860);
DISPLAY INVISIBLE (-7690 860);
FORCEPROP 2 LAST CDS_LIB mstr_discrete
J 0
(-7700 775);
PAINT MONO (-7700 775);
DISPLAY INVISIBLE (-7700 775);
FORCEPROP 1 LAST PATH I100
J 0
(-7650 925);
DISPLAY 0.978723 (-7650 925);
PAINT ORANGE (-7650 925);
DISPLAY INVISIBLE (-7650 925);
FORCEPROP 2 LAST CDS_LOCATION C3B6
J 0
(-7650 875);
DISPLAY 0.617021 (-7650 875);
PAINT AQUA (-7650 875);
DISPLAY INVISIBLE (-7650 875);
FORCEPROP 2 LAST $SEC 1
J 0
(-7650 975);
PAINT MONO (-7650 975);
DISPLAY INVISIBLE (-7650 975);
FORCEPROP 2 LAST CDS_SEC 1
J 0
(-7650 975);
PAINT MONO (-7650 975);
DISPLAY INVISIBLE (-7650 975);
FORCEADD CAPP..1
(-6175 775);
FORCEPROP 1 LAST MATERIAL TANT
J 0
(-6125 675);
DISPLAY 0.617021 (-6125 675);
PAINT SKYBLUE (-6125 675);
FORCEPROP 1 LAST VOLTAGE 16V
J 0
(-6125 725);
DISPLAY 0.617021 (-6125 725);
PAINT SKYBLUE (-6125 725);
FORCEPROP 1 LAST PACK_TYPE 3018
J 0
(-6125 625);
DISPLAY 0.617021 (-6125 625);
PAINT SKYBLUE (-6125 625);
FORCEPROP 1 LAST TOLERANCE 20%
J 0
(-6125 775);
DISPLAY 0.617021 (-6125 775);
PAINT SKYBLUE (-6125 775);
FORCEPROP 1 LAST VALUE 68UF
J 0
(-6125 825);
DISPLAY 0.617021 (-6125 825);
PAINT SKYBLUE (-6125 825);
FORCEPROP 1 LAST LOCATION C1R23
J 0
(-6125 875);
DISPLAY 0.617021 (-6125 875);
PAINT AQUA (-6125 875);
FORCEPROP 1 LAST PART_NUMBER 724613-112
J 0
(-6125 575);
DISPLAY 0.617021 (-6125 575);
PAINT BLUE (-6125 575);
FORCEPROP 1 LASTPIN (-6175 675) $PN 2
J 0
(-6165 660);
DISPLAY 0.787234 (-6165 660);
PAINT ORANGE (-6165 660);
DISPLAY INVISIBLE (-6165 660);
FORCEPROP 1 LASTPIN (-6175 875) $PN 1
J 0
(-6165 860);
DISPLAY 0.787234 (-6165 860);
PAINT ORANGE (-6165 860);
DISPLAY INVISIBLE (-6165 860);
FORCEPROP 2 LAST CDS_LIB mstr_discrete
J 0
(-6175 775);
PAINT MONO (-6175 775);
DISPLAY INVISIBLE (-6175 775);
FORCEPROP 1 LAST PATH I101
J 0
(-6125 925);
DISPLAY 0.978723 (-6125 925);
PAINT ORANGE (-6125 925);
DISPLAY INVISIBLE (-6125 925);
FORCEPROP 2 LAST CDS_LOCATION C1R23
J 0
(-6125 875);
DISPLAY 0.617021 (-6125 875);
PAINT AQUA (-6125 875);
DISPLAY INVISIBLE (-6125 875);
FORCEPROP 2 LAST $SEC 1
J 0
(-6125 975);
PAINT MONO (-6125 975);
DISPLAY INVISIBLE (-6125 975);
FORCEPROP 2 LAST CDS_SEC 1
J 0
(-6125 975);
PAINT MONO (-6125 975);
DISPLAY INVISIBLE (-6125 975);
FORCEADD CAPP..1
(-4875 775);
FORCEPROP 1 LAST MATERIAL TANT
J 0
(-4825 675);
DISPLAY 0.617021 (-4825 675);
PAINT SKYBLUE (-4825 675);
FORCEPROP 1 LAST VOLTAGE 16V
J 0
(-4825 725);
DISPLAY 0.617021 (-4825 725);
PAINT SKYBLUE (-4825 725);
FORCEPROP 1 LAST PACK_TYPE 3018
J 0
(-4825 625);
DISPLAY 0.617021 (-4825 625);
PAINT SKYBLUE (-4825 625);
FORCEPROP 1 LAST TOLERANCE 20%
J 0
(-4825 775);
DISPLAY 0.617021 (-4825 775);
PAINT SKYBLUE (-4825 775);
FORCEPROP 1 LAST VALUE 68UF
J 0
(-4825 825);
DISPLAY 0.617021 (-4825 825);
PAINT SKYBLUE (-4825 825);
FORCEPROP 1 LAST LOCATION C4M6
J 0
(-4825 875);
DISPLAY 0.617021 (-4825 875);
PAINT AQUA (-4825 875);
FORCEPROP 1 LAST PART_NUMBER 724613-112
J 0
(-4825 575);
DISPLAY 0.617021 (-4825 575);
PAINT BLUE (-4825 575);
FORCEPROP 1 LASTPIN (-4875 675) $PN 2
J 0
(-4865 660);
DISPLAY 0.787234 (-4865 660);
PAINT ORANGE (-4865 660);
DISPLAY INVISIBLE (-4865 660);
FORCEPROP 1 LASTPIN (-4875 875) $PN 1
J 0
(-4865 860);
DISPLAY 0.787234 (-4865 860);
PAINT ORANGE (-4865 860);
DISPLAY INVISIBLE (-4865 860);
FORCEPROP 2 LAST CDS_LIB mstr_discrete
J 0
(-4875 775);
PAINT MONO (-4875 775);
DISPLAY INVISIBLE (-4875 775);
FORCEPROP 1 LAST PATH I102
J 0
(-4825 925);
DISPLAY 0.978723 (-4825 925);
PAINT ORANGE (-4825 925);
DISPLAY INVISIBLE (-4825 925);
FORCEPROP 2 LAST CDS_LOCATION C4M6
J 0
(-4825 875);
DISPLAY 0.617021 (-4825 875);
PAINT AQUA (-4825 875);
DISPLAY INVISIBLE (-4825 875);
FORCEPROP 2 LAST $SEC 1
J 0
(-4825 975);
PAINT MONO (-4825 975);
DISPLAY INVISIBLE (-4825 975);
FORCEPROP 2 LAST CDS_SEC 1
J 0
(-4825 975);
PAINT MONO (-4825 975);
DISPLAY INVISIBLE (-4825 975);
FORCEADD CAPP..1
(-6550 775);
FORCEPROP 1 LAST VOLTAGE 16V
J 0
(-6500 725);
DISPLAY 0.617021 (-6500 725);
PAINT SKYBLUE (-6500 725);
FORCEPROP 1 LAST TOLERANCE 20%
J 0
(-6500 775);
DISPLAY 0.617021 (-6500 775);
PAINT SKYBLUE (-6500 775);
FORCEPROP 1 LAST MATERIAL TANT
J 0
(-6500 675);
DISPLAY 0.617021 (-6500 675);
PAINT SKYBLUE (-6500 675);
FORCEPROP 1 LAST PACK_TYPE 3018
J 0
(-6500 625);
DISPLAY 0.617021 (-6500 625);
PAINT SKYBLUE (-6500 625);
FORCEPROP 1 LAST VALUE 68UF
J 0
(-6500 825);
DISPLAY 0.617021 (-6500 825);
PAINT SKYBLUE (-6500 825);
FORCEPROP 1 LAST PART_NUMBER 724613-112
J 0
(-6575 575);
DISPLAY 0.617021 (-6575 575);
PAINT BLUE (-6575 575);
FORCEPROP 1 LAST LOCATION C1M5
J 0
(-6500 875);
DISPLAY 0.617021 (-6500 875);
PAINT AQUA (-6500 875);
FORCEPROP 1 LASTPIN (-6550 675) $PN 2
J 0
(-6540 660);
DISPLAY 0.787234 (-6540 660);
PAINT ORANGE (-6540 660);
DISPLAY INVISIBLE (-6540 660);
FORCEPROP 2 LAST CDS_LIB mstr_discrete
J 0
(-6550 775);
PAINT MONO (-6550 775);
DISPLAY INVISIBLE (-6550 775);
FORCEPROP 1 LASTPIN (-6550 875) $PN 1
J 0
(-6540 860);
DISPLAY 0.787234 (-6540 860);
PAINT ORANGE (-6540 860);
DISPLAY INVISIBLE (-6540 860);
FORCEPROP 2 LAST CDS_SEC 1
J 0
(-6500 975);
PAINT MONO (-6500 975);
DISPLAY INVISIBLE (-6500 975);
FORCEPROP 2 LAST $SEC 1
J 0
(-6500 975);
PAINT MONO (-6500 975);
DISPLAY INVISIBLE (-6500 975);
FORCEPROP 2 LAST CDS_LOCATION C1M5
J 0
(-6500 875);
DISPLAY 0.617021 (-6500 875);
PAINT AQUA (-6500 875);
DISPLAY INVISIBLE (-6500 875);
FORCEPROP 1 LAST PATH I103
J 0
(-6500 925);
DISPLAY 0.978723 (-6500 925);
PAINT ORANGE (-6500 925);
DISPLAY INVISIBLE (-6500 925);
FORCEADD CAPP..1
(-5725 1950);
FORCEPROP 1 LAST MATERIAL TANT
J 0
(-5675 1850);
DISPLAY 0.617021 (-5675 1850);
PAINT SKYBLUE (-5675 1850);
FORCEPROP 1 LAST VOLTAGE 16V
J 0
(-5675 1900);
DISPLAY 0.617021 (-5675 1900);
PAINT SKYBLUE (-5675 1900);
FORCEPROP 1 LAST PACK_TYPE 3018
J 0
(-5675 1800);
DISPLAY 0.617021 (-5675 1800);
PAINT SKYBLUE (-5675 1800);
FORCEPROP 1 LAST TOLERANCE 20%
J 0
(-5675 1950);
DISPLAY 0.617021 (-5675 1950);
PAINT SKYBLUE (-5675 1950);
FORCEPROP 1 LAST VALUE 68UF
J 0
(-5675 2000);
DISPLAY 0.617021 (-5675 2000);
PAINT SKYBLUE (-5675 2000);
FORCEPROP 1 LAST PART_NUMBER 724613-112
J 0
(-5675 1750);
DISPLAY 0.617021 (-5675 1750);
PAINT BLUE (-5675 1750);
FORCEPROP 1 LAST LOCATION C3T13
J 0
(-5675 2050);
DISPLAY 0.617021 (-5675 2050);
PAINT AQUA (-5675 2050);
FORCEPROP 1 LASTPIN (-5725 1850) $PN 2
J 0
(-5715 1835);
DISPLAY 0.787234 (-5715 1835);
PAINT ORANGE (-5715 1835);
DISPLAY INVISIBLE (-5715 1835);
FORCEPROP 2 LAST CDS_LIB mstr_discrete
J 0
(-5725 1950);
PAINT MONO (-5725 1950);
DISPLAY INVISIBLE (-5725 1950);
FORCEPROP 1 LASTPIN (-5725 2050) $PN 1
J 0
(-5715 2035);
DISPLAY 0.787234 (-5715 2035);
PAINT ORANGE (-5715 2035);
DISPLAY INVISIBLE (-5715 2035);
FORCEPROP 2 LAST CDS_SEC 1
J 0
(-5675 2150);
PAINT MONO (-5675 2150);
DISPLAY INVISIBLE (-5675 2150);
FORCEPROP 2 LAST $SEC 1
J 0
(-5675 2150);
PAINT MONO (-5675 2150);
DISPLAY INVISIBLE (-5675 2150);
FORCEPROP 2 LAST CDS_LOCATION C3T13
J 0
(-5675 2050);
DISPLAY 0.617021 (-5675 2050);
PAINT AQUA (-5675 2050);
DISPLAY INVISIBLE (-5675 2050);
FORCEPROP 1 LAST PATH I104
J 0
(-5675 2100);
DISPLAY 0.978723 (-5675 2100);
PAINT ORANGE (-5675 2100);
DISPLAY INVISIBLE (-5675 2100);
FORCEADD CAPP..1
(-4850 1950);
FORCEPROP 1 LAST TOLERANCE 20%
J 0
(-4800 1950);
DISPLAY 0.617021 (-4800 1950);
PAINT SKYBLUE (-4800 1950);
FORCEPROP 1 LAST MATERIAL TANT
J 0
(-4800 1850);
DISPLAY 0.617021 (-4800 1850);
PAINT SKYBLUE (-4800 1850);
FORCEPROP 1 LAST VALUE 68UF
J 0
(-4800 2000);
DISPLAY 0.617021 (-4800 2000);
PAINT SKYBLUE (-4800 2000);
FORCEPROP 1 LAST VOLTAGE 16V
J 0
(-4800 1900);
DISPLAY 0.617021 (-4800 1900);
PAINT SKYBLUE (-4800 1900);
FORCEPROP 1 LAST PACK_TYPE 3018
J 0
(-4800 1800);
DISPLAY 0.617021 (-4800 1800);
PAINT SKYBLUE (-4800 1800);
FORCEPROP 1 LAST PART_NUMBER 724613-112
J 0
(-4800 1750);
DISPLAY 0.617021 (-4800 1750);
PAINT BLUE (-4800 1750);
FORCEPROP 1 LAST LOCATION C4M7
J 0
(-4800 2050);
DISPLAY 0.617021 (-4800 2050);
PAINT AQUA (-4800 2050);
FORCEPROP 1 LASTPIN (-4850 1850) $PN 2
J 0
(-4840 1835);
DISPLAY 0.787234 (-4840 1835);
PAINT ORANGE (-4840 1835);
DISPLAY INVISIBLE (-4840 1835);
FORCEPROP 2 LAST CDS_LIB mstr_discrete
J 0
(-4850 1950);
PAINT MONO (-4850 1950);
DISPLAY INVISIBLE (-4850 1950);
FORCEPROP 1 LASTPIN (-4850 2050) $PN 1
J 0
(-4840 2035);
DISPLAY 0.787234 (-4840 2035);
PAINT ORANGE (-4840 2035);
DISPLAY INVISIBLE (-4840 2035);
FORCEPROP 1 LAST PATH I105
J 0
(-4800 2100);
DISPLAY 0.978723 (-4800 2100);
PAINT ORANGE (-4800 2100);
DISPLAY INVISIBLE (-4800 2100);
FORCEPROP 2 LAST CDS_LOCATION C4M7
J 0
(-4800 2050);
DISPLAY 0.617021 (-4800 2050);
PAINT AQUA (-4800 2050);
DISPLAY INVISIBLE (-4800 2050);
FORCEPROP 2 LAST $SEC 1
J 0
(-4800 2150);
PAINT MONO (-4800 2150);
DISPLAY INVISIBLE (-4800 2150);
FORCEPROP 2 LAST CDS_SEC 1
J 0
(-4800 2150);
PAINT MONO (-4800 2150);
DISPLAY INVISIBLE (-4800 2150);
FORCEADD CAPP..1
(-5275 1925);
FORCEPROP 1 LAST VOLTAGE 16V
J 0
(-5225 1875);
DISPLAY 0.617021 (-5225 1875);
PAINT SKYBLUE (-5225 1875);
FORCEPROP 1 LAST TOLERANCE 20%
J 0
(-5225 1925);
DISPLAY 0.617021 (-5225 1925);
PAINT SKYBLUE (-5225 1925);
FORCEPROP 1 LAST MATERIAL TANT
J 0
(-5225 1825);
DISPLAY 0.617021 (-5225 1825);
PAINT SKYBLUE (-5225 1825);
FORCEPROP 1 LAST PACK_TYPE 3018
J 0
(-5225 1775);
DISPLAY 0.617021 (-5225 1775);
PAINT SKYBLUE (-5225 1775);
FORCEPROP 1 LAST VALUE 68UF
J 0
(-5225 1975);
DISPLAY 0.617021 (-5225 1975);
PAINT SKYBLUE (-5225 1975);
FORCEPROP 1 LAST PART_NUMBER 724613-112
J 0
(-5225 1725);
DISPLAY 0.617021 (-5225 1725);
PAINT BLUE (-5225 1725);
FORCEPROP 1 LAST LOCATION C3T15
J 0
(-5225 2025);
DISPLAY 0.617021 (-5225 2025);
PAINT AQUA (-5225 2025);
FORCEPROP 1 LASTPIN (-5275 1825) $PN 2
J 0
(-5265 1810);
DISPLAY 0.787234 (-5265 1810);
PAINT ORANGE (-5265 1810);
DISPLAY INVISIBLE (-5265 1810);
FORCEPROP 1 LASTPIN (-5275 2025) $PN 1
J 0
(-5265 2010);
DISPLAY 0.787234 (-5265 2010);
PAINT ORANGE (-5265 2010);
DISPLAY INVISIBLE (-5265 2010);
FORCEPROP 2 LAST CDS_LIB mstr_discrete
J 0
(-5275 1925);
PAINT MONO (-5275 1925);
DISPLAY INVISIBLE (-5275 1925);
FORCEPROP 2 LAST CDS_LOCATION C3T15
J 0
(-5225 2025);
DISPLAY 0.617021 (-5225 2025);
PAINT AQUA (-5225 2025);
DISPLAY INVISIBLE (-5225 2025);
FORCEPROP 2 LAST CDS_SEC 1
J 0
(-5225 2125);
PAINT MONO (-5225 2125);
DISPLAY INVISIBLE (-5225 2125);
FORCEPROP 2 LAST $SEC 1
J 0
(-5225 2125);
PAINT MONO (-5225 2125);
DISPLAY INVISIBLE (-5225 2125);
FORCEPROP 1 LAST PATH I106
J 0
(-5225 2075);
DISPLAY 0.978723 (-5225 2075);
PAINT ORANGE (-5225 2075);
DISPLAY INVISIBLE (-5225 2075);
FORCEADD P12V_STBY..1
(-6375 2325);
FORCEPROP 3 LASTPIN (-6375 2275) SIG_NAME P12V_STBY\g
J 0
(-6365 2285);
DISPLAY 0.659574 (-6365 2285);
PAINT MONO (-6365 2285);
DISPLAY INVISIBLE (-6365 2285);
FORCEPROP 1 LAST HDL_POWER P12V_STBY
J 0
(-6675 2200);
DISPLAY 0.872340 (-6675 2200);
PAINT ORANGE (-6675 2200);
DISPLAY INVISIBLE (-6675 2200);
FORCEPROP 1 LAST BODY_TYPE PLUMBING
J 0
(-6420 2282);
DISPLAY 0.340426 (-6420 2282);
PAINT GREEN (-6420 2282);
DISPLAY INVISIBLE (-6420 2282);
FORCEPROP 1 LAST VOLTAGE 12.0V
J 0
(-6420 2282);
DISPLAY 0.340426 (-6420 2282);
PAINT SKYBLUE (-6420 2282);
DISPLAY INVISIBLE (-6420 2282);
FORCEPROP 1 LAST SIZE 1B
J 0
(-6330 2347);
DISPLAY 0.340426 (-6330 2347);
PAINT GREEN (-6330 2347);
DISPLAY INVISIBLE (-6330 2347);
FORCEPROP 2 LAST CDS_LIB mstr_symbols
J 0
(-6375 2325);
PAINT MONO (-6375 2325);
DISPLAY INVISIBLE (-6375 2325);
FORCEPROP 1 LAST PATH I107
J 0
(-6330 2327);
DISPLAY 0.340426 (-6330 2327);
PAINT GREEN (-6330 2327);
DISPLAY INVISIBLE (-6330 2327);
FORCEADD CAPP..1
(-6150 1950);
FORCEPROP 1 LAST MATERIAL TANT
J 0
(-6100 1850);
DISPLAY 0.617021 (-6100 1850);
PAINT SKYBLUE (-6100 1850);
FORCEPROP 1 LAST VOLTAGE 16V
J 0
(-6100 1900);
DISPLAY 0.617021 (-6100 1900);
PAINT SKYBLUE (-6100 1900);
FORCEPROP 1 LAST PACK_TYPE 3018
J 0
(-6100 1800);
DISPLAY 0.617021 (-6100 1800);
PAINT SKYBLUE (-6100 1800);
FORCEPROP 1 LAST TOLERANCE 20%
J 0
(-6100 1950);
DISPLAY 0.617021 (-6100 1950);
PAINT SKYBLUE (-6100 1950);
FORCEPROP 1 LAST VALUE 68UF
J 0
(-6100 2000);
DISPLAY 0.617021 (-6100 2000);
PAINT SKYBLUE (-6100 2000);
FORCEPROP 1 LAST PART_NUMBER 724613-112
J 0
(-6100 1750);
DISPLAY 0.617021 (-6100 1750);
PAINT BLUE (-6100 1750);
FORCEPROP 1 LAST LOCATION C7M6
J 0
(-6100 2050);
DISPLAY 0.617021 (-6100 2050);
PAINT AQUA (-6100 2050);
FORCEPROP 2 LAST CDS_LIB mstr_discrete
J 0
(-6150 1950);
PAINT MONO (-6150 1950);
DISPLAY INVISIBLE (-6150 1950);
FORCEPROP 1 LASTPIN (-6150 1850) $PN 2
J 0
(-6140 1835);
DISPLAY 0.787234 (-6140 1835);
PAINT ORANGE (-6140 1835);
DISPLAY INVISIBLE (-6140 1835);
FORCEPROP 1 LASTPIN (-6150 2050) $PN 1
J 0
(-6140 2035);
DISPLAY 0.787234 (-6140 2035);
PAINT ORANGE (-6140 2035);
DISPLAY INVISIBLE (-6140 2035);
FORCEPROP 2 LAST CDS_SEC 1
J 0
(-6100 2150);
PAINT MONO (-6100 2150);
DISPLAY INVISIBLE (-6100 2150);
FORCEPROP 2 LAST $SEC 1
J 0
(-6100 2150);
PAINT MONO (-6100 2150);
DISPLAY INVISIBLE (-6100 2150);
FORCEPROP 2 LAST CDS_LOCATION C7M6
J 0
(-6100 2050);
DISPLAY 0.617021 (-6100 2050);
PAINT AQUA (-6100 2050);
DISPLAY INVISIBLE (-6100 2050);
FORCEPROP 1 LAST PATH I108
J 0
(-6100 2100);
DISPLAY 0.978723 (-6100 2100);
PAINT ORANGE (-6100 2100);
DISPLAY INVISIBLE (-6100 2100);
FORCEADD CAPP..1
(-6525 1950);
FORCEPROP 1 LAST MATERIAL TANT
J 0
(-6475 1850);
DISPLAY 0.617021 (-6475 1850);
PAINT SKYBLUE (-6475 1850);
FORCEPROP 1 LAST VOLTAGE 16V
J 0
(-6475 1900);
DISPLAY 0.617021 (-6475 1900);
PAINT SKYBLUE (-6475 1900);
FORCEPROP 1 LAST PACK_TYPE 3018
J 0
(-6475 1800);
DISPLAY 0.617021 (-6475 1800);
PAINT SKYBLUE (-6475 1800);
FORCEPROP 1 LAST TOLERANCE 20%
J 0
(-6475 1950);
DISPLAY 0.617021 (-6475 1950);
PAINT SKYBLUE (-6475 1950);
FORCEPROP 1 LAST VALUE 68UF
J 0
(-6475 2000);
DISPLAY 0.617021 (-6475 2000);
PAINT SKYBLUE (-6475 2000);
FORCEPROP 1 LAST PART_NUMBER 724613-112
J 0
(-6550 1750);
DISPLAY 0.617021 (-6550 1750);
PAINT BLUE (-6550 1750);
FORCEPROP 1 LAST LOCATION C6N5
J 0
(-6475 2050);
DISPLAY 0.617021 (-6475 2050);
PAINT AQUA (-6475 2050);
FORCEPROP 1 LASTPIN (-6525 1850) $PN 2
J 0
(-6515 1835);
DISPLAY 0.787234 (-6515 1835);
PAINT ORANGE (-6515 1835);
DISPLAY INVISIBLE (-6515 1835);
FORCEPROP 2 LAST CDS_LIB mstr_discrete
J 0
(-6525 1950);
PAINT MONO (-6525 1950);
DISPLAY INVISIBLE (-6525 1950);
FORCEPROP 1 LASTPIN (-6525 2050) $PN 1
J 0
(-6515 2035);
DISPLAY 0.787234 (-6515 2035);
PAINT ORANGE (-6515 2035);
DISPLAY INVISIBLE (-6515 2035);
FORCEPROP 1 LAST PATH I109
J 0
(-6475 2100);
DISPLAY 0.978723 (-6475 2100);
PAINT ORANGE (-6475 2100);
DISPLAY INVISIBLE (-6475 2100);
FORCEPROP 2 LAST CDS_LOCATION C6N5
J 0
(-6475 2050);
DISPLAY 0.617021 (-6475 2050);
PAINT AQUA (-6475 2050);
DISPLAY INVISIBLE (-6475 2050);
FORCEPROP 2 LAST $SEC 1
J 0
(-6475 2150);
PAINT MONO (-6475 2150);
DISPLAY INVISIBLE (-6475 2150);
FORCEPROP 2 LAST CDS_SEC 1
J 0
(-6475 2150);
PAINT MONO (-6475 2150);
DISPLAY INVISIBLE (-6475 2150);
FORCEADD GND..1
(-6375 1500);
FORCEPROP 3 LASTPIN (-6375 1550) SIG_NAME GND\g
J 0
(-6365 1560);
DISPLAY 0.659574 (-6365 1560);
PAINT MONO (-6365 1560);
DISPLAY INVISIBLE (-6365 1560);
FORCEPROP 1 LAST BODY_TYPE PLUMBING
J 0
(-6420 1457);
DISPLAY 0.340426 (-6420 1457);
PAINT GREEN (-6420 1457);
DISPLAY INVISIBLE (-6420 1457);
FORCEPROP 1 LAST VOLTAGE 0.0V
J 0
(-6420 1457);
DISPLAY 0.340426 (-6420 1457);
PAINT SKYBLUE (-6420 1457);
DISPLAY INVISIBLE (-6420 1457);
FORCEPROP 1 LAST SIZE 1B
J 0
(-6300 1450);
DISPLAY 0.872340 (-6300 1450);
PAINT AQUA (-6300 1450);
DISPLAY INVISIBLE (-6300 1450);
FORCEPROP 1 LAST PATH I110
J 0
(-6300 1500);
DISPLAY 0.872340 (-6300 1500);
PAINT AQUA (-6300 1500);
DISPLAY INVISIBLE (-6300 1500);
FORCEPROP 2 LAST CDS_LIB mstr_symbols
J 0
(-6375 1500);
PAINT MONO (-6375 1500);
DISPLAY INVISIBLE (-6375 1500);
FORCEPROP 1 LAST HDL_POWER GND
J 0
(-6375 1650);
DISPLAY 0.872340 (-6375 1650);
PAINT GREEN (-6375 1650);
DISPLAY INVISIBLE (-6375 1650);
FORCEADD CAPP..1
(-6875 1950);
FORCEPROP 1 LAST MATERIAL TANT
J 0
(-6825 1850);
DISPLAY 0.617021 (-6825 1850);
PAINT SKYBLUE (-6825 1850);
FORCEPROP 1 LAST VOLTAGE 16V
J 0
(-6825 1900);
DISPLAY 0.617021 (-6825 1900);
PAINT SKYBLUE (-6825 1900);
FORCEPROP 1 LAST PACK_TYPE 3018
J 0
(-6825 1800);
DISPLAY 0.617021 (-6825 1800);
PAINT SKYBLUE (-6825 1800);
FORCEPROP 1 LAST TOLERANCE 20%
J 0
(-6825 1950);
DISPLAY 0.617021 (-6825 1950);
PAINT SKYBLUE (-6825 1950);
FORCEPROP 1 LAST VALUE 68UF
J 0
(-6825 2000);
DISPLAY 0.617021 (-6825 2000);
PAINT SKYBLUE (-6825 2000);
FORCEPROP 1 LAST PART_NUMBER 724613-112
J 0
(-6825 1750);
DISPLAY 0.617021 (-6825 1750);
PAINT BLUE (-6825 1750);
FORCEPROP 1 LAST LOCATION C9T3
J 0
(-6825 2050);
DISPLAY 0.617021 (-6825 2050);
PAINT AQUA (-6825 2050);
FORCEPROP 1 LASTPIN (-6875 1850) $PN 2
J 0
(-6865 1835);
DISPLAY 0.787234 (-6865 1835);
PAINT ORANGE (-6865 1835);
DISPLAY INVISIBLE (-6865 1835);
FORCEPROP 2 LAST CDS_LIB mstr_discrete
J 0
(-6875 1950);
PAINT MONO (-6875 1950);
DISPLAY INVISIBLE (-6875 1950);
FORCEPROP 1 LASTPIN (-6875 2050) $PN 1
J 0
(-6865 2035);
DISPLAY 0.787234 (-6865 2035);
PAINT ORANGE (-6865 2035);
DISPLAY INVISIBLE (-6865 2035);
FORCEPROP 1 LAST PATH I111
J 0
(-6825 2100);
DISPLAY 0.978723 (-6825 2100);
PAINT ORANGE (-6825 2100);
DISPLAY INVISIBLE (-6825 2100);
FORCEPROP 2 LAST CDS_LOCATION C9T3
J 0
(-6825 2050);
DISPLAY 0.617021 (-6825 2050);
PAINT AQUA (-6825 2050);
DISPLAY INVISIBLE (-6825 2050);
FORCEPROP 2 LAST $SEC 1
J 0
(-6825 2150);
PAINT MONO (-6825 2150);
DISPLAY INVISIBLE (-6825 2150);
FORCEPROP 2 LAST CDS_SEC 1
J 0
(-6825 2150);
PAINT MONO (-6825 2150);
DISPLAY INVISIBLE (-6825 2150);
FORCEADD CAPP..1
(-7250 1950);
FORCEPROP 1 LAST MATERIAL TANT
J 0
(-7200 1850);
DISPLAY 0.617021 (-7200 1850);
PAINT SKYBLUE (-7200 1850);
FORCEPROP 1 LAST VOLTAGE 16V
J 0
(-7200 1900);
DISPLAY 0.617021 (-7200 1900);
PAINT SKYBLUE (-7200 1900);
FORCEPROP 1 LAST PACK_TYPE 3018
J 0
(-7200 1800);
DISPLAY 0.617021 (-7200 1800);
PAINT SKYBLUE (-7200 1800);
FORCEPROP 1 LAST TOLERANCE 20%
J 0
(-7200 1950);
DISPLAY 0.617021 (-7200 1950);
PAINT SKYBLUE (-7200 1950);
FORCEPROP 1 LAST VALUE 68UF
J 0
(-7200 2000);
DISPLAY 0.617021 (-7200 2000);
PAINT SKYBLUE (-7200 2000);
FORCEPROP 1 LAST PART_NUMBER 724613-112
J 0
(-7200 1750);
DISPLAY 0.617021 (-7200 1750);
PAINT BLUE (-7200 1750);
FORCEPROP 1 LAST LOCATION C4F4
J 0
(-7200 2050);
DISPLAY 0.617021 (-7200 2050);
PAINT AQUA (-7200 2050);
FORCEPROP 1 LASTPIN (-7250 1850) $PN 2
J 0
(-7240 1835);
DISPLAY 0.787234 (-7240 1835);
PAINT ORANGE (-7240 1835);
DISPLAY INVISIBLE (-7240 1835);
FORCEPROP 2 LAST CDS_LIB mstr_discrete
J 0
(-7250 1950);
PAINT MONO (-7250 1950);
DISPLAY INVISIBLE (-7250 1950);
FORCEPROP 1 LASTPIN (-7250 2050) $PN 1
J 0
(-7240 2035);
DISPLAY 0.787234 (-7240 2035);
PAINT ORANGE (-7240 2035);
DISPLAY INVISIBLE (-7240 2035);
FORCEPROP 2 LAST CDS_SEC 1
J 0
(-7200 2150);
PAINT MONO (-7200 2150);
DISPLAY INVISIBLE (-7200 2150);
FORCEPROP 2 LAST $SEC 1
J 0
(-7200 2150);
PAINT MONO (-7200 2150);
DISPLAY INVISIBLE (-7200 2150);
FORCEPROP 2 LAST CDS_LOCATION C4F4
J 0
(-7200 2050);
DISPLAY 0.617021 (-7200 2050);
PAINT AQUA (-7200 2050);
DISPLAY INVISIBLE (-7200 2050);
FORCEPROP 1 LAST PATH I112
J 0
(-7200 2100);
DISPLAY 0.978723 (-7200 2100);
PAINT ORANGE (-7200 2100);
DISPLAY INVISIBLE (-7200 2100);
FORCEADD CAPP..1
(-7675 1950);
FORCEPROP 1 LAST VALUE 68UF
J 0
(-7625 2000);
DISPLAY 0.617021 (-7625 2000);
PAINT SKYBLUE (-7625 2000);
FORCEPROP 1 LAST TOLERANCE 20%
J 0
(-7625 1950);
DISPLAY 0.617021 (-7625 1950);
PAINT SKYBLUE (-7625 1950);
FORCEPROP 1 LAST VOLTAGE 16V
J 0
(-7625 1900);
DISPLAY 0.617021 (-7625 1900);
PAINT SKYBLUE (-7625 1900);
FORCEPROP 1 LAST PACK_TYPE 3018
J 0
(-7625 1800);
DISPLAY 0.617021 (-7625 1800);
PAINT SKYBLUE (-7625 1800);
FORCEPROP 1 LAST MATERIAL TANT
J 0
(-7625 1850);
DISPLAY 0.617021 (-7625 1850);
PAINT SKYBLUE (-7625 1850);
FORCEPROP 1 LAST PART_NUMBER 724613-112
J 0
(-7625 1750);
DISPLAY 0.617021 (-7625 1750);
PAINT BLUE (-7625 1750);
FORCEPROP 1 LAST LOCATION C3T3
J 0
(-7625 2050);
DISPLAY 0.617021 (-7625 2050);
PAINT AQUA (-7625 2050);
FORCEPROP 1 LASTPIN (-7675 1850) $PN 2
J 0
(-7665 1835);
DISPLAY 0.787234 (-7665 1835);
PAINT ORANGE (-7665 1835);
DISPLAY INVISIBLE (-7665 1835);
FORCEPROP 2 LAST CDS_LIB mstr_discrete
J 0
(-7675 1950);
PAINT MONO (-7675 1950);
DISPLAY INVISIBLE (-7675 1950);
FORCEPROP 1 LASTPIN (-7675 2050) $PN 1
J 0
(-7665 2035);
DISPLAY 0.787234 (-7665 2035);
PAINT ORANGE (-7665 2035);
DISPLAY INVISIBLE (-7665 2035);
FORCEPROP 2 LAST CDS_SEC 1
J 0
(-7625 2150);
PAINT MONO (-7625 2150);
DISPLAY INVISIBLE (-7625 2150);
FORCEPROP 2 LAST $SEC 1
J 0
(-7625 2150);
PAINT MONO (-7625 2150);
DISPLAY INVISIBLE (-7625 2150);
FORCEPROP 2 LAST CDS_LOCATION C3T3
J 0
(-7625 2050);
DISPLAY 0.617021 (-7625 2050);
PAINT AQUA (-7625 2050);
DISPLAY INVISIBLE (-7625 2050);
FORCEPROP 1 LAST PATH I113
J 0
(-7625 2100);
DISPLAY 0.978723 (-7625 2100);
PAINT ORANGE (-7625 2100);
DISPLAY INVISIBLE (-7625 2100);
FORCEADD P12V_PSU..1
(-3700 2750);
FORCEPROP 3 LASTPIN (-3700 2700) SIG_NAME P12V_PSU\g
J 0
(-3690 2710);
DISPLAY 0.659574 (-3690 2710);
PAINT MONO (-3690 2710);
DISPLAY INVISIBLE (-3690 2710);
FORCEPROP 1 LAST VOLTAGE 12.0
J 0
(-3745 2707);
DISPLAY 0.340426 (-3745 2707);
PAINT SKYBLUE (-3745 2707);
DISPLAY INVISIBLE (-3745 2707);
FORCEPROP 2 LAST BOM_COST NT_BASE_VRD
J 0
(-3700 2850);
DISPLAY 0.617021 (-3700 2850);
PAINT ORANGE (-3700 2850);
DISPLAY INVISIBLE (-3700 2850);
FORCEPROP 2 LAST CDS_LIB mstr_symbols
J 0
(-3700 2750);
PAINT ORANGE (-3700 2750);
DISPLAY INVISIBLE (-3700 2750);
FORCEPROP 1 LAST BODY_TYPE PLUMBING
J 0
(-3745 2707);
DISPLAY 0.340426 (-3745 2707);
PAINT GREEN (-3745 2707);
DISPLAY INVISIBLE (-3745 2707);
FORCEPROP 1 LAST PATH I25
J 0
(-3650 2775);
DISPLAY 0.872340 (-3650 2775);
PAINT AQUA (-3650 2775);
DISPLAY INVISIBLE (-3650 2775);
FORCEPROP 2 LAST ROOM P2V5_LAN_AUX_VR
J 0
(-3700 2850);
DISPLAY 0.617021 (-3700 2850);
PAINT ORANGE (-3700 2850);
DISPLAY INVISIBLE (-3700 2850);
FORCEPROP 1 LAST HDL_POWER P12V_PSU
J 1
(-3700 2800);
DISPLAY 0.872340 (-3700 2800);
PAINT GREEN (-3700 2800);
DISPLAY INVISIBLE (-3700 2800);
FORCEADD CONN3_G98259001..1
(-925 3725);
FORCEPROP 1 LAST MATERIAL CONN
J 0
(-1075 3950);
DISPLAY 0.617021 (-1075 3950);
PAINT SKYBLUE (-1075 3950);
FORCEPROP 1 LAST PART_NUMBER G98259-001
J 0
(-1075 3475);
DISPLAY 0.617021 (-1075 3475);
PAINT BLUE (-1075 3475);
FORCEPROP 1 LAST LOCATION RM1E1
J 0
(-1075 4000);
DISPLAY 0.617021 (-1075 4000);
PAINT AQUA (-1075 4000);
FORCEPROP 2 LASTPIN (-725 3675) $PN 3
J 0
(-715 3685);
DISPLAY 0.617021 (-715 3685);
PAINT MONO (-715 3685);
FORCEPROP 2 LASTPIN (-725 3575) $PN 2
J 0
(-715 3585);
DISPLAY 0.617021 (-715 3585);
PAINT MONO (-715 3585);
FORCEPROP 2 LASTPIN (-725 3775) $PN 1
J 0
(-715 3785);
DISPLAY 0.617021 (-715 3785);
PAINT MONO (-715 3785);
FORCEPROP 2 LAST CDS_LOCATION RM1E1
J 0
(-1075 4000);
DISPLAY 0.617021 (-1075 4000);
PAINT AQUA (-1075 4000);
DISPLAY INVISIBLE (-1075 4000);
FORCEPROP 2 LAST $SEC 1
J 0
(-1075 4050);
PAINT MONO (-1075 4050);
DISPLAY INVISIBLE (-1075 4050);
FORCEPROP 2 LAST CDS_SEC 1
J 0
(-1075 4050);
PAINT MONO (-1075 4050);
DISPLAY INVISIBLE (-1075 4050);
FORCEPROP 1 LAST PACK_TYPE PIP
J 0
(-1075 4050);
PAINT SKYBLUE (-1075 4050);
DISPLAY INVISIBLE (-1075 4050);
FORCEPROP 1 LAST CDS_LMAN_SYM_OUTLINE -150,200,150,-200
J 0
(-925 3725);
DISPLAY 0.468085 (-925 3725);
PAINT GREEN (-925 3725);
DISPLAY INVISIBLE (-925 3725);
FORCEPROP 2 LAST CDS_LIB mstr_conn
J 0
(-925 3725);
PAINT ORANGE (-925 3725);
DISPLAY INVISIBLE (-925 3725);
FORCEPROP 1 LAST PATH I26
J 0
(-825 3951);
PAINT GREEN (-825 3951);
DISPLAY INVISIBLE (-825 3951);
FORCEADD GND..1
(-475 3375);
FORCEPROP 3 LASTPIN (-475 3425) SIG_NAME GND\g
J 0
(-465 3435);
DISPLAY 0.659574 (-465 3435);
PAINT MONO (-465 3435);
DISPLAY INVISIBLE (-465 3435);
FORCEPROP 1 LAST VOLTAGE 0.0V
J 0
(-520 3332);
DISPLAY 0.340426 (-520 3332);
PAINT SKYBLUE (-520 3332);
DISPLAY INVISIBLE (-520 3332);
FORCEPROP 1 LAST BODY_TYPE PLUMBING
J 0
(-520 3332);
DISPLAY 0.340426 (-520 3332);
PAINT GREEN (-520 3332);
DISPLAY INVISIBLE (-520 3332);
FORCEPROP 1 LAST SIZE 1B
J 0
(-400 3325);
DISPLAY 0.872340 (-400 3325);
PAINT AQUA (-400 3325);
DISPLAY INVISIBLE (-400 3325);
FORCEPROP 2 LAST CDS_LIB mstr_symbols
J 0
(-475 3375);
PAINT ORANGE (-475 3375);
DISPLAY INVISIBLE (-475 3375);
FORCEPROP 1 LAST PATH I27
J 0
(-400 3375);
DISPLAY 0.872340 (-400 3375);
PAINT AQUA (-400 3375);
DISPLAY INVISIBLE (-400 3375);
FORCEPROP 1 LAST HDL_POWER GND
J 0
(-475 3525);
DISPLAY 0.872340 (-475 3525);
PAINT GREEN (-475 3525);
DISPLAY INVISIBLE (-475 3525);
FORCEADD GND..1
(-3550 1900);
FORCEPROP 3 LASTPIN (-3550 1950) SIG_NAME GND\g
J 0
(-3540 1960);
DISPLAY 0.659574 (-3540 1960);
PAINT MONO (-3540 1960);
DISPLAY INVISIBLE (-3540 1960);
FORCEPROP 1 LAST VOLTAGE 0.0V
J 0
(-3595 1857);
DISPLAY 0.340426 (-3595 1857);
PAINT SKYBLUE (-3595 1857);
DISPLAY INVISIBLE (-3595 1857);
FORCEPROP 1 LAST SIZE 1B
J 0
(-3475 1850);
DISPLAY 0.872340 (-3475 1850);
PAINT AQUA (-3475 1850);
DISPLAY INVISIBLE (-3475 1850);
FORCEPROP 2 LAST CDS_LIB mstr_symbols
J 0
(-3550 1900);
PAINT ORANGE (-3550 1900);
DISPLAY INVISIBLE (-3550 1900);
FORCEPROP 1 LAST BODY_TYPE PLUMBING
J 0
(-3595 1857);
DISPLAY 0.340426 (-3595 1857);
PAINT GREEN (-3595 1857);
DISPLAY INVISIBLE (-3595 1857);
FORCEPROP 1 LAST PATH I28
J 0
(-3475 1900);
DISPLAY 0.872340 (-3475 1900);
PAINT AQUA (-3475 1900);
DISPLAY INVISIBLE (-3475 1900);
FORCEPROP 1 LAST HDL_POWER GND
J 0
(-3550 2050);
DISPLAY 0.872340 (-3550 2050);
PAINT GREEN (-3550 2050);
DISPLAY INVISIBLE (-3550 2050);
FORCEADD CONN12_G98257001..1
(-3025 2250);
FORCEPROP 1 LAST PART_NUMBER G98257-001
J 0
(-3225 1950);
DISPLAY 0.617021 (-3225 1950);
PAINT BLUE (-3225 1950);
FORCEPROP 2 LASTPIN (-3275 2350) $PN B1
J 2
(-3285 2360);
DISPLAY 0.617021 (-3285 2360);
PAINT ORANGE (-3285 2360);
FORCEPROP 2 LASTPIN (-3275 2300) $PN B2
J 2
(-3285 2310);
DISPLAY 0.617021 (-3285 2310);
PAINT ORANGE (-3285 2310);
FORCEPROP 2 LASTPIN (-3275 2250) $PN B3
J 2
(-3285 2260);
DISPLAY 0.617021 (-3285 2260);
PAINT ORANGE (-3285 2260);
FORCEPROP 2 LASTPIN (-3275 2150) $PN C1
J 2
(-3285 2160);
DISPLAY 0.617021 (-3285 2160);
PAINT ORANGE (-3285 2160);
FORCEPROP 2 LASTPIN (-3275 2100) $PN C2
J 2
(-3285 2110);
DISPLAY 0.617021 (-3285 2110);
PAINT ORANGE (-3285 2110);
FORCEPROP 2 LASTPIN (-3275 2050) $PN C3
J 2
(-3285 2060);
DISPLAY 0.617021 (-3285 2060);
PAINT ORANGE (-3285 2060);
FORCEPROP 1 LAST MATERIAL CONN
J 0
(-3225 2525);
DISPLAY 0.617021 (-3225 2525);
PAINT SKYBLUE (-3225 2525);
FORCEPROP 1 LAST LOCATION J1E1
J 0
(-3225 2575);
DISPLAY 0.617021 (-3225 2575);
PAINT AQUA (-3225 2575);
FORCEPROP 2 LASTPIN (-2775 2050) $PN D3
J 0
(-2765 2060);
DISPLAY 0.617021 (-2765 2060);
PAINT ORANGE (-2765 2060);
FORCEPROP 2 LASTPIN (-2775 2100) $PN D2
J 0
(-2765 2110);
DISPLAY 0.617021 (-2765 2110);
PAINT ORANGE (-2765 2110);
FORCEPROP 2 LASTPIN (-2775 2150) $PN D1
J 0
(-2765 2160);
DISPLAY 0.617021 (-2765 2160);
PAINT ORANGE (-2765 2160);
FORCEPROP 2 LASTPIN (-2775 2250) $PN A3
J 0
(-2765 2260);
DISPLAY 0.617021 (-2765 2260);
PAINT ORANGE (-2765 2260);
FORCEPROP 2 LASTPIN (-2775 2350) $PN A1
J 0
(-2765 2360);
DISPLAY 0.617021 (-2765 2360);
PAINT ORANGE (-2765 2360);
FORCEPROP 2 LASTPIN (-2775 2300) $PN A2
J 0
(-2765 2310);
DISPLAY 0.617021 (-2765 2310);
PAINT ORANGE (-2765 2310);
FORCEPROP 0 LAST ROOM HOT_SWAP
J 0
(-3275 2700);
DISPLAY 1.021277 (-3275 2700);
PAINT ORANGE (-3275 2700);
DISPLAY INVISIBLE (-3275 2700);
FORCEPROP 2 LAST CDS_LOCATION J1E1
J 0
(-3225 2575);
DISPLAY 0.617021 (-3225 2575);
PAINT AQUA (-3225 2575);
DISPLAY INVISIBLE (-3225 2575);
FORCEPROP 2 LAST SEC 1
J 0
(-3225 2625);
DISPLAY 0.680851 (-3225 2625);
PAINT MONO (-3225 2625);
DISPLAY INVISIBLE (-3225 2625);
FORCEPROP 2 LAST SEC_TYPE THMT
J 0
(-3225 2625);
DISPLAY 1.021277 (-3225 2625);
PAINT ORANGE (-3225 2625);
DISPLAY INVISIBLE (-3225 2625);
FORCEPROP 1 LAST PACK_TYPE THMT
J 0
(-3225 2625);
PAINT SKYBLUE (-3225 2625);
DISPLAY INVISIBLE (-3225 2625);
FORCEPROP 1 LAST CDS_LMAN_SYM_OUTLINE -200,250,200,-250
J 0
(-3025 2250);
DISPLAY 0.468085 (-3025 2250);
PAINT GREEN (-3025 2250);
DISPLAY INVISIBLE (-3025 2250);
FORCEPROP 2 LAST CDS_LIB mstr_conn
J 0
(-3025 2250);
PAINT ORANGE (-3025 2250);
DISPLAY INVISIBLE (-3025 2250);
FORCEPROP 1 LAST PATH I29
J 0
(-2925 2526);
PAINT GREEN (-2925 2526);
DISPLAY INVISIBLE (-2925 2526);
FORCEADD GND..1
(-3700 3425);
FORCEPROP 3 LASTPIN (-3700 3475) SIG_NAME GND\g
J 0
(-3690 3485);
DISPLAY 0.659574 (-3690 3485);
PAINT MONO (-3690 3485);
DISPLAY INVISIBLE (-3690 3485);
FORCEPROP 1 LAST VOLTAGE 0.0V
J 0
(-3745 3382);
DISPLAY 0.340426 (-3745 3382);
PAINT SKYBLUE (-3745 3382);
DISPLAY INVISIBLE (-3745 3382);
FORCEPROP 1 LAST BODY_TYPE PLUMBING
J 0
(-3745 3382);
DISPLAY 0.340426 (-3745 3382);
PAINT GREEN (-3745 3382);
DISPLAY INVISIBLE (-3745 3382);
FORCEPROP 1 LAST SIZE 1B
J 0
(-3625 3375);
DISPLAY 0.872340 (-3625 3375);
PAINT AQUA (-3625 3375);
DISPLAY INVISIBLE (-3625 3375);
FORCEPROP 1 LAST PATH I30
J 0
(-3625 3425);
DISPLAY 0.872340 (-3625 3425);
PAINT AQUA (-3625 3425);
DISPLAY INVISIBLE (-3625 3425);
FORCEPROP 2 LAST CDS_LIB mstr_symbols
J 0
(-3700 3425);
PAINT ORANGE (-3700 3425);
DISPLAY INVISIBLE (-3700 3425);
FORCEPROP 1 LAST HDL_POWER GND
J 0
(-3700 3575);
DISPLAY 0.872340 (-3700 3575);
PAINT GREEN (-3700 3575);
DISPLAY INVISIBLE (-3700 3575);
FORCEADD CAP..1
(-3700 3675);
FORCEPROP 1 LASTPIN (-3700 3575) $PN 2
J 0
(-3690 3555);
DISPLAY 0.617021 (-3690 3555);
PAINT ORANGE (-3690 3555);
FORCEPROP 1 LASTPIN (-3700 3775) $PN 1
J 0
(-3690 3755);
DISPLAY 0.617021 (-3690 3755);
PAINT ORANGE (-3690 3755);
FORCEPROP 1 LAST MATERIAL X6S
J 0
(-3650 3575);
DISPLAY 0.617021 (-3650 3575);
PAINT SKYBLUE (-3650 3575);
FORCEPROP 1 LAST VOLTAGE 16V
J 0
(-3650 3675);
DISPLAY 0.617021 (-3650 3675);
PAINT SKYBLUE (-3650 3675);
FORCEPROP 1 LAST PACK_TYPE 0805
J 0
(-3650 3475);
DISPLAY 0.617021 (-3650 3475);
PAINT SKYBLUE (-3650 3475);
FORCEPROP 1 LAST TOLERANCE 10%
J 0
(-3650 3625);
DISPLAY 0.617021 (-3650 3625);
PAINT SKYBLUE (-3650 3625);
FORCEPROP 1 LAST VALUE 10UF
J 0
(-3650 3725);
DISPLAY 0.617021 (-3650 3725);
PAINT SKYBLUE (-3650 3725);
FORCEPROP 1 LAST PART_NUMBER C95333-007
J 0
(-3650 3525);
DISPLAY 0.617021 (-3650 3525);
PAINT BLUE (-3650 3525);
FORCEPROP 1 LAST LOCATION C9R5
J 0
(-3650 3775);
DISPLAY 0.617021 (-3650 3775);
PAINT AQUA (-3650 3775);
FORCEPROP 2 LAST CDS_LOCATION C9R5
J 0
(-3650 3775);
DISPLAY 0.617021 (-3650 3775);
PAINT AQUA (-3650 3775);
DISPLAY INVISIBLE (-3650 3775);
FORCEPROP 2 LAST CDS_LIB mstr_discrete
J 0
(-3700 3675);
PAINT ORANGE (-3700 3675);
DISPLAY INVISIBLE (-3700 3675);
FORCEPROP 2 LAST ROOM HOT_SWAP
J 0
(-3650 3825);
DISPLAY 1.361702 (-3650 3825);
PAINT ORANGE (-3650 3825);
DISPLAY INVISIBLE (-3650 3825);
FORCEPROP 1 LAST PATH I31
J 0
(-3650 3825);
DISPLAY 0.978723 (-3650 3825);
PAINT WHITE (-3650 3825);
DISPLAY INVISIBLE (-3650 3825);
FORCEPROP 2 LAST SEC 1
J 0
(-3650 3875);
DISPLAY 0.680851 (-3650 3875);
PAINT MONO (-3650 3875);
DISPLAY INVISIBLE (-3650 3875);
FORCEPROP 2 LAST SEC_TYPE 0805
J 0
(-3650 3875);
DISPLAY 1.021277 (-3650 3875);
PAINT ORANGE (-3650 3875);
DISPLAY INVISIBLE (-3650 3875);
FORCEADD CAP..1
(-3375 3675);
FORCEPROP 1 LASTPIN (-3375 3575) $PN 2
J 0
(-3365 3555);
DISPLAY 0.617021 (-3365 3555);
PAINT ORANGE (-3365 3555);
FORCEPROP 1 LAST PACK_TYPE 0805
J 0
(-3325 3475);
DISPLAY 0.617021 (-3325 3475);
PAINT SKYBLUE (-3325 3475);
FORCEPROP 1 LAST MATERIAL X6S
J 0
(-3325 3575);
DISPLAY 0.617021 (-3325 3575);
PAINT SKYBLUE (-3325 3575);
FORCEPROP 1 LASTPIN (-3375 3775) $PN 1
J 0
(-3365 3755);
DISPLAY 0.617021 (-3365 3755);
PAINT ORANGE (-3365 3755);
FORCEPROP 1 LAST LOCATION C1E12
J 0
(-3325 3775);
DISPLAY 0.617021 (-3325 3775);
PAINT AQUA (-3325 3775);
FORCEPROP 1 LAST VALUE 10UF
J 0
(-3325 3725);
DISPLAY 0.617021 (-3325 3725);
PAINT SKYBLUE (-3325 3725);
FORCEPROP 1 LAST VOLTAGE 16V
J 0
(-3325 3675);
DISPLAY 0.617021 (-3325 3675);
PAINT SKYBLUE (-3325 3675);
FORCEPROP 1 LAST TOLERANCE 10%
J 0
(-3325 3625);
DISPLAY 0.617021 (-3325 3625);
PAINT SKYBLUE (-3325 3625);
FORCEPROP 1 LAST PART_NUMBER C95333-007
J 0
(-3325 3525);
DISPLAY 0.617021 (-3325 3525);
PAINT BLUE (-3325 3525);
FORCEPROP 2 LAST CDS_LIB mstr_discrete
J 0
(-3375 3675);
PAINT ORANGE (-3375 3675);
DISPLAY INVISIBLE (-3375 3675);
FORCEPROP 2 LAST ROOM HOT_SWAP
J 0
(-3325 3825);
DISPLAY 1.361702 (-3325 3825);
PAINT ORANGE (-3325 3825);
DISPLAY INVISIBLE (-3325 3825);
FORCEPROP 1 LAST PATH I32
J 0
(-3325 3825);
DISPLAY 0.978723 (-3325 3825);
PAINT WHITE (-3325 3825);
DISPLAY INVISIBLE (-3325 3825);
FORCEPROP 2 LAST CDS_LOCATION C1E12
J 0
(-3325 3775);
DISPLAY 0.617021 (-3325 3775);
PAINT AQUA (-3325 3775);
DISPLAY INVISIBLE (-3325 3775);
FORCEPROP 2 LAST SEC 1
J 0
(-3325 3875);
DISPLAY 0.680851 (-3325 3875);
PAINT MONO (-3325 3875);
DISPLAY INVISIBLE (-3325 3875);
FORCEPROP 2 LAST SEC_TYPE 0805
J 0
(-3325 3875);
DISPLAY 1.021277 (-3325 3875);
PAINT ORANGE (-3325 3875);
DISPLAY INVISIBLE (-3325 3875);
FORCEADD GND..1
(-2450 1900);
FORCEPROP 3 LASTPIN (-2450 1950) SIG_NAME GND\g
J 0
(-2440 1960);
DISPLAY 0.659574 (-2440 1960);
PAINT MONO (-2440 1960);
DISPLAY INVISIBLE (-2440 1960);
FORCEPROP 1 LAST PATH I33
J 0
(-2375 1900);
DISPLAY 0.872340 (-2375 1900);
PAINT AQUA (-2375 1900);
DISPLAY INVISIBLE (-2375 1900);
FORCEPROP 1 LAST BODY_TYPE PLUMBING
J 0
(-2495 1857);
DISPLAY 0.340426 (-2495 1857);
PAINT GREEN (-2495 1857);
DISPLAY INVISIBLE (-2495 1857);
FORCEPROP 1 LAST SIZE 1B
J 0
(-2375 1850);
DISPLAY 0.872340 (-2375 1850);
PAINT AQUA (-2375 1850);
DISPLAY INVISIBLE (-2375 1850);
FORCEPROP 2 LAST CDS_LIB mstr_symbols
J 0
(-2450 1900);
PAINT ORANGE (-2450 1900);
DISPLAY INVISIBLE (-2450 1900);
FORCEPROP 1 LAST VOLTAGE 0.0V
J 0
(-2495 1857);
DISPLAY 0.340426 (-2495 1857);
PAINT SKYBLUE (-2495 1857);
DISPLAY INVISIBLE (-2495 1857);
FORCEPROP 1 LAST HDL_POWER GND
J 0
(-2450 2050);
DISPLAY 0.872340 (-2450 2050);
PAINT GREEN (-2450 2050);
DISPLAY INVISIBLE (-2450 2050);
FORCEADD P12V_PSU..1
(-2325 2750);
FORCEPROP 3 LASTPIN (-2325 2700) SIG_NAME P12V_PSU\g
J 0
(-2315 2710);
DISPLAY 0.659574 (-2315 2710);
PAINT MONO (-2315 2710);
DISPLAY INVISIBLE (-2315 2710);
FORCEPROP 1 LAST HDL_POWER P12V_PSU
J 1
(-2325 2800);
DISPLAY 0.872340 (-2325 2800);
PAINT GREEN (-2325 2800);
DISPLAY INVISIBLE (-2325 2800);
FORCEPROP 1 LAST VOLTAGE 12.0
J 0
(-2370 2707);
DISPLAY 0.340426 (-2370 2707);
PAINT SKYBLUE (-2370 2707);
DISPLAY INVISIBLE (-2370 2707);
FORCEPROP 2 LAST CDS_LIB mstr_symbols
J 0
(-2325 2750);
PAINT ORANGE (-2325 2750);
DISPLAY INVISIBLE (-2325 2750);
FORCEPROP 2 LAST BOM_COST NT_BASE_VRD
J 0
(-2325 2850);
DISPLAY 0.617021 (-2325 2850);
PAINT ORANGE (-2325 2850);
DISPLAY INVISIBLE (-2325 2850);
FORCEPROP 1 LAST BODY_TYPE PLUMBING
J 0
(-2370 2707);
DISPLAY 0.340426 (-2370 2707);
PAINT GREEN (-2370 2707);
DISPLAY INVISIBLE (-2370 2707);
FORCEPROP 1 LAST PATH I34
J 0
(-2275 2775);
DISPLAY 0.872340 (-2275 2775);
PAINT AQUA (-2275 2775);
DISPLAY INVISIBLE (-2275 2775);
FORCEPROP 2 LAST ROOM P2V5_LAN_AUX_VR
J 0
(-2325 2850);
DISPLAY 0.617021 (-2325 2850);
PAINT ORANGE (-2325 2850);
DISPLAY INVISIBLE (-2325 2850);
FORCEADD CAP..1
(-3025 3675);
FORCEPROP 1 LAST PACK_TYPE 0805
J 0
(-2975 3475);
DISPLAY 0.617021 (-2975 3475);
PAINT SKYBLUE (-2975 3475);
FORCEPROP 1 LASTPIN (-3025 3575) $PN 2
J 0
(-3015 3555);
DISPLAY 0.617021 (-3015 3555);
PAINT ORANGE (-3015 3555);
FORCEPROP 1 LAST PART_NUMBER C95333-007
J 0
(-2975 3525);
DISPLAY 0.617021 (-2975 3525);
PAINT BLUE (-2975 3525);
FORCEPROP 1 LAST MATERIAL X6S
J 0
(-2975 3575);
DISPLAY 0.617021 (-2975 3575);
PAINT SKYBLUE (-2975 3575);
FORCEPROP 1 LASTPIN (-3025 3775) $PN 1
J 0
(-3015 3755);
DISPLAY 0.617021 (-3015 3755);
PAINT ORANGE (-3015 3755);
FORCEPROP 1 LAST VOLTAGE 16V
J 0
(-2975 3675);
DISPLAY 0.617021 (-2975 3675);
PAINT SKYBLUE (-2975 3675);
FORCEPROP 1 LAST TOLERANCE 10%
J 0
(-2975 3625);
DISPLAY 0.617021 (-2975 3625);
PAINT SKYBLUE (-2975 3625);
FORCEPROP 1 LAST VALUE 10UF
J 0
(-2975 3725);
DISPLAY 0.617021 (-2975 3725);
PAINT SKYBLUE (-2975 3725);
FORCEPROP 1 LAST LOCATION C1E15
J 0
(-2975 3775);
DISPLAY 0.617021 (-2975 3775);
PAINT AQUA (-2975 3775);
FORCEPROP 2 LAST CDS_LIB mstr_discrete
J 0
(-3025 3675);
PAINT ORANGE (-3025 3675);
DISPLAY INVISIBLE (-3025 3675);
FORCEPROP 2 LAST CDS_LOCATION C1E15
J 0
(-2975 3775);
DISPLAY 0.617021 (-2975 3775);
PAINT AQUA (-2975 3775);
DISPLAY INVISIBLE (-2975 3775);
FORCEPROP 1 LAST PATH I35
J 0
(-2975 3825);
DISPLAY 0.978723 (-2975 3825);
PAINT WHITE (-2975 3825);
DISPLAY INVISIBLE (-2975 3825);
FORCEPROP 2 LAST ROOM HOT_SWAP
J 0
(-2975 3825);
DISPLAY 1.361702 (-2975 3825);
PAINT ORANGE (-2975 3825);
DISPLAY INVISIBLE (-2975 3825);
FORCEPROP 2 LAST SEC_TYPE 0805
J 0
(-2975 3875);
DISPLAY 1.021277 (-2975 3875);
PAINT ORANGE (-2975 3875);
DISPLAY INVISIBLE (-2975 3875);
FORCEPROP 2 LAST SEC 1
J 0
(-2975 3875);
DISPLAY 0.680851 (-2975 3875);
PAINT MONO (-2975 3875);
DISPLAY INVISIBLE (-2975 3875);
FORCEADD CAP_A..1
(-2675 3675);
FORCEPROP 1 LASTPIN (-2675 3575) $PN 2
J 0
(-2665 3555);
DISPLAY 0.617021 (-2665 3555);
PAINT ORANGE (-2665 3555);
FORCEPROP 1 LASTPIN (-2675 3775) $PN 1
J 0
(-2665 3755);
DISPLAY 0.617021 (-2665 3755);
PAINT ORANGE (-2665 3755);
FORCEPROP 1 LAST MATERIAL X7R
J 0
(-2625 3575);
DISPLAY 0.617021 (-2625 3575);
PAINT SKYBLUE (-2625 3575);
FORCEPROP 1 LAST VOLTAGE 16V
J 0
(-2625 3675);
DISPLAY 0.617021 (-2625 3675);
PAINT SKYBLUE (-2625 3675);
FORCEPROP 1 LAST PACK_TYPE 0402V
J 0
(-2625 3475);
DISPLAY 0.617021 (-2625 3475);
PAINT SKYBLUE (-2625 3475);
FORCEPROP 1 LAST TOLERANCE 10%
J 0
(-2625 3625);
DISPLAY 0.617021 (-2625 3625);
PAINT SKYBLUE (-2625 3625);
FORCEPROP 1 LAST VALUE 0.1UF
J 0
(-2625 3725);
DISPLAY 0.617021 (-2625 3725);
PAINT SKYBLUE (-2625 3725);
FORCEPROP 1 LAST PART_NUMBER A36096-030
J 0
(-2625 3525);
DISPLAY 0.617021 (-2625 3525);
PAINT BLUE (-2625 3525);
FORCEPROP 1 LAST LOCATION C9R12
J 0
(-2625 3775);
DISPLAY 0.617021 (-2625 3775);
PAINT AQUA (-2625 3775);
FORCEPROP 2 LAST CDS_LOCATION C9R12
J 0
(-2625 3775);
DISPLAY 0.617021 (-2625 3775);
PAINT AQUA (-2625 3775);
DISPLAY INVISIBLE (-2625 3775);
FORCEPROP 0 LAST ROOM HOT_SWAP
J 0
(-2625 3750);
DISPLAY 0.978723 (-2625 3750);
PAINT GREEN (-2625 3750);
DISPLAY INVISIBLE (-2625 3750);
FORCEPROP 2 LAST CDS_LIB dev_discrete
J 0
(-2675 3675);
PAINT ORANGE (-2675 3675);
DISPLAY INVISIBLE (-2675 3675);
FORCEPROP 2 LAST CDS_SEC 1
J 0
(-2625 3825);
PAINT ORANGE (-2625 3825);
DISPLAY INVISIBLE (-2625 3825);
FORCEPROP 2 LAST BOM_COST HOT_SWAP
J 0
(-2575 3825);
PAINT MONO (-2575 3825);
DISPLAY INVISIBLE (-2575 3825);
FORCEPROP 1 LAST PATH I36
J 0
(-2625 3825);
DISPLAY 0.978723 (-2625 3825);
PAINT WHITE (-2625 3825);
DISPLAY INVISIBLE (-2625 3825);
FORCEPROP 2 LAST SEC 1
J 0
(-2625 3875);
DISPLAY 0.680851 (-2625 3875);
PAINT MONO (-2625 3875);
DISPLAY INVISIBLE (-2625 3875);
FORCEPROP 2 LAST SEC_TYPE 0402V
J 0
(-2625 3875);
DISPLAY 1.021277 (-2625 3875);
PAINT ORANGE (-2625 3875);
DISPLAY INVISIBLE (-2625 3875);
FORCEADD CAP_A..1
(-2300 3675);
FORCEPROP 1 LASTPIN (-2300 3575) $PN 2
J 0
(-2290 3555);
DISPLAY 0.617021 (-2290 3555);
PAINT ORANGE (-2290 3555);
FORCEPROP 1 LAST PACK_TYPE 0402V
J 0
(-2250 3475);
DISPLAY 0.617021 (-2250 3475);
PAINT SKYBLUE (-2250 3475);
FORCEPROP 1 LAST MATERIAL X7R
J 0
(-2250 3575);
DISPLAY 0.617021 (-2250 3575);
PAINT SKYBLUE (-2250 3575);
FORCEPROP 1 LASTPIN (-2300 3775) $PN 1
J 0
(-2290 3755);
DISPLAY 0.617021 (-2290 3755);
PAINT ORANGE (-2290 3755);
FORCEPROP 1 LAST VOLTAGE 16V
J 0
(-2250 3675);
DISPLAY 0.617021 (-2250 3675);
PAINT SKYBLUE (-2250 3675);
FORCEPROP 1 LAST LOCATION C9R6
J 0
(-2250 3775);
DISPLAY 0.617021 (-2250 3775);
PAINT AQUA (-2250 3775);
FORCEPROP 1 LAST VALUE 0.1UF
J 0
(-2250 3725);
DISPLAY 0.617021 (-2250 3725);
PAINT SKYBLUE (-2250 3725);
FORCEPROP 1 LAST TOLERANCE 10%
J 0
(-2250 3625);
DISPLAY 0.617021 (-2250 3625);
PAINT SKYBLUE (-2250 3625);
FORCEPROP 1 LAST PART_NUMBER A36096-030
J 0
(-2250 3525);
DISPLAY 0.617021 (-2250 3525);
PAINT BLUE (-2250 3525);
FORCEPROP 2 LAST CDS_LIB dev_discrete
J 0
(-2300 3675);
PAINT ORANGE (-2300 3675);
DISPLAY INVISIBLE (-2300 3675);
FORCEPROP 2 LAST CDS_LOCATION C9R6
J 0
(-2250 3775);
DISPLAY 0.617021 (-2250 3775);
PAINT AQUA (-2250 3775);
DISPLAY INVISIBLE (-2250 3775);
FORCEPROP 0 LAST ROOM HOT_SWAP
J 0
(-2250 3750);
DISPLAY 0.978723 (-2250 3750);
PAINT GREEN (-2250 3750);
DISPLAY INVISIBLE (-2250 3750);
FORCEPROP 1 LAST PATH I37
J 0
(-2250 3825);
DISPLAY 0.978723 (-2250 3825);
PAINT WHITE (-2250 3825);
DISPLAY INVISIBLE (-2250 3825);
FORCEPROP 2 LAST BOM_COST HOT_SWAP
J 0
(-2200 3825);
PAINT MONO (-2200 3825);
DISPLAY INVISIBLE (-2200 3825);
FORCEPROP 2 LAST CDS_SEC 1
J 0
(-2250 3825);
PAINT ORANGE (-2250 3825);
DISPLAY INVISIBLE (-2250 3825);
FORCEPROP 2 LAST SEC_TYPE 0402V
J 0
(-2250 3875);
DISPLAY 1.021277 (-2250 3875);
PAINT ORANGE (-2250 3875);
DISPLAY INVISIBLE (-2250 3875);
FORCEPROP 2 LAST SEC 1
J 0
(-2250 3875);
DISPLAY 0.680851 (-2250 3875);
PAINT MONO (-2250 3875);
DISPLAY INVISIBLE (-2250 3875);
FORCEADD CAP_A..1
(-1950 3675);
FORCEPROP 1 LASTPIN (-1950 3575) $PN 2
J 0
(-1940 3555);
DISPLAY 0.617021 (-1940 3555);
PAINT ORANGE (-1940 3555);
FORCEPROP 1 LAST PART_NUMBER A36096-030
J 0
(-1900 3525);
DISPLAY 0.617021 (-1900 3525);
PAINT BLUE (-1900 3525);
FORCEPROP 1 LAST PACK_TYPE 0402V
J 0
(-1900 3475);
DISPLAY 0.617021 (-1900 3475);
PAINT SKYBLUE (-1900 3475);
FORCEPROP 1 LAST MATERIAL X7R
J 0
(-1900 3575);
DISPLAY 0.617021 (-1900 3575);
PAINT SKYBLUE (-1900 3575);
FORCEPROP 1 LASTPIN (-1950 3775) $PN 1
J 0
(-1940 3755);
DISPLAY 0.617021 (-1940 3755);
PAINT ORANGE (-1940 3755);
FORCEPROP 1 LAST VOLTAGE 16V
J 0
(-1900 3675);
DISPLAY 0.617021 (-1900 3675);
PAINT SKYBLUE (-1900 3675);
FORCEPROP 1 LAST TOLERANCE 10%
J 0
(-1900 3625);
DISPLAY 0.617021 (-1900 3625);
PAINT SKYBLUE (-1900 3625);
FORCEPROP 1 LAST VALUE 0.1UF
J 0
(-1900 3725);
DISPLAY 0.617021 (-1900 3725);
PAINT SKYBLUE (-1900 3725);
FORCEPROP 1 LAST LOCATION C1E17
J 0
(-1900 3775);
DISPLAY 0.617021 (-1900 3775);
PAINT AQUA (-1900 3775);
FORCEPROP 2 LAST CDS_LIB dev_discrete
J 0
(-1950 3675);
PAINT ORANGE (-1950 3675);
DISPLAY INVISIBLE (-1950 3675);
FORCEPROP 2 LAST CDS_LOCATION C1E17
J 0
(-1900 3775);
DISPLAY 0.617021 (-1900 3775);
PAINT AQUA (-1900 3775);
DISPLAY INVISIBLE (-1900 3775);
FORCEPROP 0 LAST ROOM HOT_SWAP
J 0
(-1900 3750);
DISPLAY 0.978723 (-1900 3750);
PAINT GREEN (-1900 3750);
DISPLAY INVISIBLE (-1900 3750);
FORCEPROP 1 LAST PATH I38
J 0
(-1900 3825);
DISPLAY 0.978723 (-1900 3825);
PAINT WHITE (-1900 3825);
DISPLAY INVISIBLE (-1900 3825);
FORCEPROP 2 LAST BOM_COST HOT_SWAP
J 0
(-1850 3825);
PAINT MONO (-1850 3825);
DISPLAY INVISIBLE (-1850 3825);
FORCEPROP 2 LAST CDS_SEC 1
J 0
(-1900 3825);
PAINT ORANGE (-1900 3825);
DISPLAY INVISIBLE (-1900 3825);
FORCEPROP 2 LAST SEC_TYPE 0402V
J 0
(-1900 3875);
DISPLAY 1.021277 (-1900 3875);
PAINT ORANGE (-1900 3875);
DISPLAY INVISIBLE (-1900 3875);
FORCEPROP 2 LAST SEC 1
J 0
(-1900 3875);
DISPLAY 0.680851 (-1900 3875);
PAINT MONO (-1900 3875);
DISPLAY INVISIBLE (-1900 3875);
FORCEADD CAP_A..1
(-1625 3675);
FORCEPROP 1 LASTPIN (-1625 3575) $PN 2
J 0
(-1615 3555);
DISPLAY 0.617021 (-1615 3555);
PAINT ORANGE (-1615 3555);
FORCEPROP 1 LASTPIN (-1625 3775) $PN 1
J 0
(-1615 3755);
DISPLAY 0.617021 (-1615 3755);
PAINT ORANGE (-1615 3755);
FORCEPROP 1 LAST MATERIAL X7R
J 0
(-1575 3575);
DISPLAY 0.617021 (-1575 3575);
PAINT SKYBLUE (-1575 3575);
FORCEPROP 1 LAST VOLTAGE 16V
J 0
(-1575 3675);
DISPLAY 0.617021 (-1575 3675);
PAINT SKYBLUE (-1575 3675);
FORCEPROP 1 LAST PACK_TYPE 0402V
J 0
(-1575 3475);
DISPLAY 0.617021 (-1575 3475);
PAINT SKYBLUE (-1575 3475);
FORCEPROP 1 LAST TOLERANCE 10%
J 0
(-1575 3625);
DISPLAY 0.617021 (-1575 3625);
PAINT SKYBLUE (-1575 3625);
FORCEPROP 1 LAST VALUE 0.1UF
J 0
(-1575 3725);
DISPLAY 0.617021 (-1575 3725);
PAINT SKYBLUE (-1575 3725);
FORCEPROP 1 LAST PART_NUMBER A36096-030
J 0
(-1575 3525);
DISPLAY 0.617021 (-1575 3525);
PAINT BLUE (-1575 3525);
FORCEPROP 1 LAST LOCATION C1E16
J 0
(-1575 3775);
DISPLAY 0.617021 (-1575 3775);
PAINT AQUA (-1575 3775);
FORCEPROP 2 LAST CDS_LIB dev_discrete
J 0
(-1625 3675);
PAINT ORANGE (-1625 3675);
DISPLAY INVISIBLE (-1625 3675);
FORCEPROP 2 LAST CDS_LOCATION C1E16
J 0
(-1575 3775);
DISPLAY 0.617021 (-1575 3775);
PAINT AQUA (-1575 3775);
DISPLAY INVISIBLE (-1575 3775);
FORCEPROP 0 LAST ROOM HOT_SWAP
J 0
(-1575 3750);
DISPLAY 0.978723 (-1575 3750);
PAINT GREEN (-1575 3750);
DISPLAY INVISIBLE (-1575 3750);
FORCEPROP 2 LAST CDS_SEC 1
J 0
(-1575 3825);
PAINT ORANGE (-1575 3825);
DISPLAY INVISIBLE (-1575 3825);
FORCEPROP 1 LAST PATH I39
J 0
(-1575 3825);
DISPLAY 0.978723 (-1575 3825);
PAINT WHITE (-1575 3825);
DISPLAY INVISIBLE (-1575 3825);
FORCEPROP 2 LAST SEC 1
J 0
(-1575 3875);
DISPLAY 0.680851 (-1575 3875);
PAINT MONO (-1575 3875);
DISPLAY INVISIBLE (-1575 3875);
FORCEPROP 2 LAST SEC_TYPE 0402V
J 0
(-1575 3875);
DISPLAY 1.021277 (-1575 3875);
PAINT ORANGE (-1575 3875);
DISPLAY INVISIBLE (-1575 3875);
FORCEPROP 2 LAST BOM_COST HOT_SWAP
J 0
(-1525 3825);
PAINT MONO (-1525 3825);
DISPLAY INVISIBLE (-1525 3825);
FORCEADD P12V_PSU..1
(-1625 4025);
FORCEPROP 3 LASTPIN (-1625 3975) SIG_NAME P12V_PSU\g
J 0
(-1615 3985);
DISPLAY 0.659574 (-1615 3985);
PAINT MONO (-1615 3985);
DISPLAY INVISIBLE (-1615 3985);
FORCEPROP 1 LAST VOLTAGE 12.0
J 0
(-1670 3982);
DISPLAY 0.340426 (-1670 3982);
PAINT SKYBLUE (-1670 3982);
DISPLAY INVISIBLE (-1670 3982);
FORCEPROP 2 LAST CDS_LIB mstr_symbols
J 0
(-1625 4025);
PAINT ORANGE (-1625 4025);
DISPLAY INVISIBLE (-1625 4025);
FORCEPROP 1 LAST BODY_TYPE PLUMBING
J 0
(-1670 3982);
DISPLAY 0.340426 (-1670 3982);
PAINT GREEN (-1670 3982);
DISPLAY INVISIBLE (-1670 3982);
FORCEPROP 1 LAST PATH I40
J 0
(-1575 4050);
DISPLAY 0.872340 (-1575 4050);
PAINT AQUA (-1575 4050);
DISPLAY INVISIBLE (-1575 4050);
FORCEPROP 1 LAST HDL_POWER P12V_PSU
J 1
(-1625 4075);
DISPLAY 0.872340 (-1625 4075);
PAINT GREEN (-1625 4075);
DISPLAY INVISIBLE (-1625 4075);
FORCEPROP 2 LAST ROOM P2V5_LAN_AUX_VR
J 0
(-1625 4125);
DISPLAY 0.617021 (-1625 4125);
PAINT ORANGE (-1625 4125);
DISPLAY INVISIBLE (-1625 4125);
FORCEPROP 2 LAST BOM_COST NT_BASE_VRD
J 0
(-1625 4125);
DISPLAY 0.617021 (-1625 4125);
PAINT ORANGE (-1625 4125);
DISPLAY INVISIBLE (-1625 4125);
FORCEADD GND..1
(-6900 4525);
FORCEPROP 3 LASTPIN (-6900 4575) SIG_NAME GND\g
J 0
(-6890 4585);
DISPLAY 0.659574 (-6890 4585);
PAINT MONO (-6890 4585);
DISPLAY INVISIBLE (-6890 4585);
FORCEPROP 1 LAST VOLTAGE 0.0V
J 0
(-6945 4482);
DISPLAY 0.340426 (-6945 4482);
PAINT SKYBLUE (-6945 4482);
DISPLAY INVISIBLE (-6945 4482);
FORCEPROP 1 LAST BODY_TYPE PLUMBING
J 0
(-6945 4482);
DISPLAY 0.340426 (-6945 4482);
PAINT GREEN (-6945 4482);
DISPLAY INVISIBLE (-6945 4482);
FORCEPROP 2 LAST CDS_LIB mstr_symbols
J 0
(-6900 4525);
PAINT ORANGE (-6900 4525);
DISPLAY INVISIBLE (-6900 4525);
FORCEPROP 1 LAST SIZE 1B
J 0
(-6825 4475);
DISPLAY 0.872340 (-6825 4475);
PAINT AQUA (-6825 4475);
DISPLAY INVISIBLE (-6825 4475);
FORCEPROP 1 LAST PATH I48
J 0
(-6825 4525);
DISPLAY 0.872340 (-6825 4525);
PAINT AQUA (-6825 4525);
DISPLAY INVISIBLE (-6825 4525);
FORCEPROP 1 LAST HDL_POWER GND
J 0
(-6900 4675);
DISPLAY 0.872340 (-6900 4675);
PAINT GREEN (-6900 4675);
DISPLAY INVISIBLE (-6900 4675);
FORCEADD MTG_KEYHOLE..1
(-6475 4725);
FORCEPROP 2 LASTPIN (-6725 4725) $PN 1
J 2
(-6735 4735);
DISPLAY 0.617021 (-6735 4735);
PAINT MONO (-6735 4735);
FORCEPROP 1 LAST PART_NUMBER NA
J 0
(-6675 4575);
DISPLAY 0.617021 (-6675 4575);
PAINT BLUE (-6675 4575);
FORCEPROP 1 LAST LOCATION TH4G1
J 0
(-6675 4925);
DISPLAY 0.617021 (-6675 4925);
PAINT AQUA (-6675 4925);
FORCEPROP 1 LAST MATERIAL EMPTY
J 0
(-6675 4875);
DISPLAY 0.617021 (-6675 4875);
PAINT RED (-6675 4875);
FORCEPROP 2 LAST $SEC 1
J 0
(-6675 4975);
DISPLAY 0.680851 (-6675 4975);
PAINT MONO (-6675 4975);
DISPLAY INVISIBLE (-6675 4975);
FORCEPROP 0 LAST ROOM MOUNTING_HOLES
J 0
(-6675 4975);
DISPLAY 1.021277 (-6675 4975);
PAINT ORANGE (-6675 4975);
DISPLAY INVISIBLE (-6675 4975);
FORCEPROP 2 LAST CDS_LOCATION TH4G1
J 0
(-6675 4925);
DISPLAY 0.617021 (-6675 4925);
PAINT AQUA (-6675 4925);
DISPLAY INVISIBLE (-6675 4925);
FORCEPROP 0 LAST BOM_COST TEST_MFG
J 0
(-6675 5025);
DISPLAY 1.021277 (-6675 5025);
PAINT ORANGE (-6675 5025);
DISPLAY INVISIBLE (-6675 5025);
FORCEPROP 2 LAST CDS_SEC 1
J 0
(-6675 4975);
DISPLAY 1.021277 (-6675 4975);
PAINT ORANGE (-6675 4975);
DISPLAY INVISIBLE (-6675 4975);
FORCEPROP 1 LAST PACK_TYPE TH
J 0
(-6675 4975);
DISPLAY 0.978723 (-6675 4975);
PAINT SKYBLUE (-6675 4975);
DISPLAY INVISIBLE (-6675 4975);
FORCEPROP 2 LAST CDS_LIB mstr_misc
J 0
(-6475 4725);
PAINT ORANGE (-6475 4725);
DISPLAY INVISIBLE (-6475 4725);
FORCEPROP 1 LAST PATH I49
J 0
(-6475 4875);
DISPLAY 0.978723 (-6475 4875);
PAINT GREEN (-6475 4875);
DISPLAY INVISIBLE (-6475 4875);
FORCEADD MTG_KEYHOLE..1
(-6425 4125);
FORCEPROP 1 LAST PART_NUMBER NA
J 0
(-6625 3975);
DISPLAY 0.617021 (-6625 3975);
PAINT BLUE (-6625 3975);
FORCEPROP 2 LASTPIN (-6675 4125) $PN 1
J 2
(-6685 4135);
DISPLAY 0.617021 (-6685 4135);
PAINT MONO (-6685 4135);
FORCEPROP 1 LAST LOCATION TH9G1
J 0
(-6625 4325);
DISPLAY 0.617021 (-6625 4325);
PAINT AQUA (-6625 4325);
FORCEPROP 1 LAST MATERIAL EMPTY
J 0
(-6625 4275);
DISPLAY 0.617021 (-6625 4275);
PAINT RED (-6625 4275);
FORCEPROP 2 LAST CDS_LOCATION TH9G1
J 0
(-6625 4325);
DISPLAY 0.617021 (-6625 4325);
PAINT AQUA (-6625 4325);
DISPLAY INVISIBLE (-6625 4325);
FORCEPROP 2 LAST CDS_LIB mstr_misc
J 0
(-6425 4125);
PAINT ORANGE (-6425 4125);
DISPLAY INVISIBLE (-6425 4125);
FORCEPROP 1 LAST PATH I52
J 0
(-6425 4275);
DISPLAY 0.978723 (-6425 4275);
PAINT GREEN (-6425 4275);
DISPLAY INVISIBLE (-6425 4275);
FORCEPROP 0 LAST ROOM MOUNTING_HOLES
J 0
(-6625 4375);
DISPLAY 1.021277 (-6625 4375);
PAINT ORANGE (-6625 4375);
DISPLAY INVISIBLE (-6625 4375);
FORCEPROP 2 LAST $SEC 1
J 0
(-6625 4375);
DISPLAY 0.680851 (-6625 4375);
PAINT MONO (-6625 4375);
DISPLAY INVISIBLE (-6625 4375);
FORCEPROP 2 LAST CDS_SEC 1
J 0
(-6625 4375);
DISPLAY 1.021277 (-6625 4375);
PAINT ORANGE (-6625 4375);
DISPLAY INVISIBLE (-6625 4375);
FORCEPROP 0 LAST BOM_COST TEST_MFG
J 0
(-6625 4425);
DISPLAY 1.021277 (-6625 4425);
PAINT ORANGE (-6625 4425);
DISPLAY INVISIBLE (-6625 4425);
FORCEPROP 1 LAST PACK_TYPE TH
J 0
(-6625 4375);
DISPLAY 0.978723 (-6625 4375);
PAINT SKYBLUE (-6625 4375);
DISPLAY INVISIBLE (-6625 4375);
FORCEADD GND..1
(-6850 3925);
FORCEPROP 3 LASTPIN (-6850 3975) SIG_NAME GND\g
J 0
(-6840 3985);
DISPLAY 0.659574 (-6840 3985);
PAINT MONO (-6840 3985);
DISPLAY INVISIBLE (-6840 3985);
FORCEPROP 1 LAST VOLTAGE 0.0V
J 0
(-6895 3882);
DISPLAY 0.340426 (-6895 3882);
PAINT SKYBLUE (-6895 3882);
DISPLAY INVISIBLE (-6895 3882);
FORCEPROP 2 LAST CDS_LIB mstr_symbols
J 0
(-6850 3925);
PAINT ORANGE (-6850 3925);
DISPLAY INVISIBLE (-6850 3925);
FORCEPROP 1 LAST SIZE 1B
J 0
(-6775 3875);
DISPLAY 0.872340 (-6775 3875);
PAINT AQUA (-6775 3875);
DISPLAY INVISIBLE (-6775 3875);
FORCEPROP 1 LAST BODY_TYPE PLUMBING
J 0
(-6895 3882);
DISPLAY 0.340426 (-6895 3882);
PAINT GREEN (-6895 3882);
DISPLAY INVISIBLE (-6895 3882);
FORCEPROP 1 LAST PATH I53
J 0
(-6775 3925);
DISPLAY 0.872340 (-6775 3925);
PAINT AQUA (-6775 3925);
DISPLAY INVISIBLE (-6775 3925);
FORCEPROP 1 LAST HDL_POWER GND
J 0
(-6850 4075);
DISPLAY 0.872340 (-6850 4075);
PAINT GREEN (-6850 4075);
DISPLAY INVISIBLE (-6850 4075);
FORCEADD MTG_KEYHOLE..1
(-4600 4725);
FORCEPROP 1 LAST PART_NUMBER NA
J 0
(-4800 4575);
DISPLAY 0.617021 (-4800 4575);
PAINT BLUE (-4800 4575);
FORCEPROP 2 LASTPIN (-4850 4725) $PN 1
J 2
(-4860 4735);
DISPLAY 0.617021 (-4860 4735);
PAINT MONO (-4860 4735);
FORCEPROP 1 LAST LOCATION TH9A1
J 0
(-4775 4950);
DISPLAY 0.617021 (-4775 4950);
PAINT AQUA (-4775 4950);
FORCEPROP 1 LAST MATERIAL EMPTY
J 0
(-4800 4875);
DISPLAY 0.617021 (-4800 4875);
PAINT RED (-4800 4875);
FORCEPROP 0 LAST ROOM MOUNTING_HOLES
J 0
(-4800 4975);
DISPLAY 1.021277 (-4800 4975);
PAINT ORANGE (-4800 4975);
DISPLAY INVISIBLE (-4800 4975);
FORCEPROP 2 LAST CDS_LOCATION TH9A1
J 0
(-4775 4950);
DISPLAY 0.617021 (-4775 4950);
PAINT AQUA (-4775 4950);
DISPLAY INVISIBLE (-4775 4950);
FORCEPROP 2 LAST $SEC 1
J 0
(-4800 4975);
DISPLAY 0.680851 (-4800 4975);
PAINT MONO (-4800 4975);
DISPLAY INVISIBLE (-4800 4975);
FORCEPROP 2 LAST CDS_SEC 1
J 0
(-4800 4975);
DISPLAY 1.021277 (-4800 4975);
PAINT ORANGE (-4800 4975);
DISPLAY INVISIBLE (-4800 4975);
FORCEPROP 0 LAST BOM_COST TEST_MFG
J 0
(-4800 5025);
DISPLAY 1.021277 (-4800 5025);
PAINT ORANGE (-4800 5025);
DISPLAY INVISIBLE (-4800 5025);
FORCEPROP 1 LAST PACK_TYPE TH
J 0
(-4800 4975);
DISPLAY 0.978723 (-4800 4975);
PAINT SKYBLUE (-4800 4975);
DISPLAY INVISIBLE (-4800 4975);
FORCEPROP 2 LAST CDS_LIB mstr_misc
J 0
(-4600 4725);
PAINT ORANGE (-4600 4725);
DISPLAY INVISIBLE (-4600 4725);
FORCEPROP 1 LAST PATH I54
J 0
(-4600 4875);
DISPLAY 0.978723 (-4600 4875);
PAINT GREEN (-4600 4875);
DISPLAY INVISIBLE (-4600 4875);
FORCEADD GND..1
(-5025 4525);
FORCEPROP 3 LASTPIN (-5025 4575) SIG_NAME GND\g
J 0
(-5015 4585);
DISPLAY 0.659574 (-5015 4585);
PAINT MONO (-5015 4585);
DISPLAY INVISIBLE (-5015 4585);
FORCEPROP 1 LAST PATH I55
J 0
(-4950 4525);
DISPLAY 0.872340 (-4950 4525);
PAINT AQUA (-4950 4525);
DISPLAY INVISIBLE (-4950 4525);
FORCEPROP 1 LAST BODY_TYPE PLUMBING
J 0
(-5070 4482);
DISPLAY 0.340426 (-5070 4482);
PAINT GREEN (-5070 4482);
DISPLAY INVISIBLE (-5070 4482);
FORCEPROP 2 LAST CDS_LIB mstr_symbols
J 0
(-5025 4525);
PAINT ORANGE (-5025 4525);
DISPLAY INVISIBLE (-5025 4525);
FORCEPROP 1 LAST SIZE 1B
J 0
(-4950 4475);
DISPLAY 0.872340 (-4950 4475);
PAINT AQUA (-4950 4475);
DISPLAY INVISIBLE (-4950 4475);
FORCEPROP 1 LAST VOLTAGE 0.0V
J 0
(-5070 4482);
DISPLAY 0.340426 (-5070 4482);
PAINT SKYBLUE (-5070 4482);
DISPLAY INVISIBLE (-5070 4482);
FORCEPROP 1 LAST HDL_POWER GND
J 0
(-5025 4675);
DISPLAY 0.872340 (-5025 4675);
PAINT GREEN (-5025 4675);
DISPLAY INVISIBLE (-5025 4675);
FORCEADD MTG_KEYHOLE..1
(-5525 4725);
FORCEPROP 1 LAST PART_NUMBER NA
J 0
(-5725 4575);
DISPLAY 0.617021 (-5725 4575);
PAINT BLUE (-5725 4575);
FORCEPROP 2 LASTPIN (-5775 4725) $PN 1
J 2
(-5785 4735);
DISPLAY 0.617021 (-5785 4735);
PAINT MONO (-5785 4735);
FORCEPROP 1 LAST LOCATION TH1A1
J 0
(-5725 4950);
DISPLAY 0.617021 (-5725 4950);
PAINT AQUA (-5725 4950);
FORCEPROP 1 LAST MATERIAL EMPTY
J 0
(-5725 4875);
DISPLAY 0.617021 (-5725 4875);
PAINT RED (-5725 4875);
FORCEPROP 1 LAST PACK_TYPE TH
J 0
(-5725 4975);
DISPLAY 0.978723 (-5725 4975);
PAINT SKYBLUE (-5725 4975);
DISPLAY INVISIBLE (-5725 4975);
FORCEPROP 0 LAST BOM_COST TEST_MFG
J 0
(-5725 5025);
DISPLAY 1.021277 (-5725 5025);
PAINT ORANGE (-5725 5025);
DISPLAY INVISIBLE (-5725 5025);
FORCEPROP 2 LAST CDS_SEC 1
J 0
(-5725 4975);
DISPLAY 1.021277 (-5725 4975);
PAINT ORANGE (-5725 4975);
DISPLAY INVISIBLE (-5725 4975);
FORCEPROP 2 LAST $SEC 1
J 0
(-5725 4975);
DISPLAY 0.680851 (-5725 4975);
PAINT MONO (-5725 4975);
DISPLAY INVISIBLE (-5725 4975);
FORCEPROP 2 LAST CDS_LOCATION TH1A1
J 0
(-5725 4950);
DISPLAY 0.617021 (-5725 4950);
PAINT AQUA (-5725 4950);
DISPLAY INVISIBLE (-5725 4950);
FORCEPROP 0 LAST ROOM MOUNTING_HOLES
J 0
(-5725 4975);
DISPLAY 1.021277 (-5725 4975);
PAINT ORANGE (-5725 4975);
DISPLAY INVISIBLE (-5725 4975);
FORCEPROP 2 LAST CDS_LIB mstr_misc
J 0
(-5525 4725);
PAINT ORANGE (-5525 4725);
DISPLAY INVISIBLE (-5525 4725);
FORCEPROP 1 LAST PATH I56
J 0
(-5525 4875);
DISPLAY 0.978723 (-5525 4875);
PAINT GREEN (-5525 4875);
DISPLAY INVISIBLE (-5525 4875);
FORCEADD GND..1
(-5950 4525);
FORCEPROP 3 LASTPIN (-5950 4575) SIG_NAME GND\g
J 0
(-5940 4585);
DISPLAY 0.659574 (-5940 4585);
PAINT MONO (-5940 4585);
DISPLAY INVISIBLE (-5940 4585);
FORCEPROP 1 LAST BODY_TYPE PLUMBING
J 0
(-5995 4482);
DISPLAY 0.340426 (-5995 4482);
PAINT GREEN (-5995 4482);
DISPLAY INVISIBLE (-5995 4482);
FORCEPROP 2 LAST CDS_LIB mstr_symbols
J 0
(-5950 4525);
PAINT ORANGE (-5950 4525);
DISPLAY INVISIBLE (-5950 4525);
FORCEPROP 1 LAST VOLTAGE 0.0V
J 0
(-5995 4482);
DISPLAY 0.340426 (-5995 4482);
PAINT SKYBLUE (-5995 4482);
DISPLAY INVISIBLE (-5995 4482);
FORCEPROP 1 LAST PATH I57
J 0
(-5875 4525);
DISPLAY 0.872340 (-5875 4525);
PAINT AQUA (-5875 4525);
DISPLAY INVISIBLE (-5875 4525);
FORCEPROP 1 LAST SIZE 1B
J 0
(-5875 4475);
DISPLAY 0.872340 (-5875 4475);
PAINT AQUA (-5875 4475);
DISPLAY INVISIBLE (-5875 4475);
FORCEPROP 1 LAST HDL_POWER GND
J 0
(-5950 4675);
DISPLAY 0.872340 (-5950 4675);
PAINT GREEN (-5950 4675);
DISPLAY INVISIBLE (-5950 4675);
FORCEADD MTG_KEYHOLE..1
(-7350 4125);
FORCEPROP 1 LAST PART_NUMBER NA
J 0
(-7550 3975);
DISPLAY 0.617021 (-7550 3975);
PAINT BLUE (-7550 3975);
FORCEPROP 2 LASTPIN (-7600 4125) $PN 1
J 2
(-7610 4135);
DISPLAY 0.617021 (-7610 4135);
PAINT MONO (-7610 4135);
FORCEPROP 1 LAST LOCATION TH4A1
J 0
(-7550 4325);
DISPLAY 0.617021 (-7550 4325);
PAINT AQUA (-7550 4325);
FORCEPROP 1 LAST MATERIAL EMPTY
J 0
(-7550 4275);
DISPLAY 0.617021 (-7550 4275);
PAINT RED (-7550 4275);
FORCEPROP 0 LAST ROOM MOUNTING_HOLES
J 0
(-7550 4375);
DISPLAY 1.021277 (-7550 4375);
PAINT ORANGE (-7550 4375);
DISPLAY INVISIBLE (-7550 4375);
FORCEPROP 2 LAST CDS_LOCATION TH4A1
J 0
(-7550 4325);
DISPLAY 0.617021 (-7550 4325);
PAINT AQUA (-7550 4325);
DISPLAY INVISIBLE (-7550 4325);
FORCEPROP 2 LAST $SEC 1
J 0
(-7550 4375);
DISPLAY 0.680851 (-7550 4375);
PAINT MONO (-7550 4375);
DISPLAY INVISIBLE (-7550 4375);
FORCEPROP 2 LAST CDS_SEC 1
J 0
(-7550 4375);
DISPLAY 1.021277 (-7550 4375);
PAINT ORANGE (-7550 4375);
DISPLAY INVISIBLE (-7550 4375);
FORCEPROP 0 LAST BOM_COST TEST_MFG
J 0
(-7550 4425);
DISPLAY 1.021277 (-7550 4425);
PAINT ORANGE (-7550 4425);
DISPLAY INVISIBLE (-7550 4425);
FORCEPROP 1 LAST PACK_TYPE TH
J 0
(-7550 4375);
DISPLAY 0.978723 (-7550 4375);
PAINT SKYBLUE (-7550 4375);
DISPLAY INVISIBLE (-7550 4375);
FORCEPROP 2 LAST CDS_LIB mstr_misc
J 0
(-7350 4125);
PAINT ORANGE (-7350 4125);
DISPLAY INVISIBLE (-7350 4125);
FORCEPROP 1 LAST PATH I62
J 0
(-7350 4275);
DISPLAY 0.978723 (-7350 4275);
PAINT GREEN (-7350 4275);
DISPLAY INVISIBLE (-7350 4275);
FORCEADD GND..1
(-7775 3925);
FORCEPROP 3 LASTPIN (-7775 3975) SIG_NAME GND\g
J 0
(-7765 3985);
DISPLAY 0.659574 (-7765 3985);
PAINT MONO (-7765 3985);
DISPLAY INVISIBLE (-7765 3985);
FORCEPROP 1 LAST PATH I63
J 0
(-7700 3925);
DISPLAY 0.872340 (-7700 3925);
PAINT AQUA (-7700 3925);
DISPLAY INVISIBLE (-7700 3925);
FORCEPROP 1 LAST BODY_TYPE PLUMBING
J 0
(-7820 3882);
DISPLAY 0.340426 (-7820 3882);
PAINT GREEN (-7820 3882);
DISPLAY INVISIBLE (-7820 3882);
FORCEPROP 1 LAST SIZE 1B
J 0
(-7700 3875);
DISPLAY 0.872340 (-7700 3875);
PAINT AQUA (-7700 3875);
DISPLAY INVISIBLE (-7700 3875);
FORCEPROP 2 LAST CDS_LIB mstr_symbols
J 0
(-7775 3925);
PAINT ORANGE (-7775 3925);
DISPLAY INVISIBLE (-7775 3925);
FORCEPROP 1 LAST VOLTAGE 0.0V
J 0
(-7820 3882);
DISPLAY 0.340426 (-7820 3882);
PAINT SKYBLUE (-7820 3882);
DISPLAY INVISIBLE (-7820 3882);
FORCEPROP 1 LAST HDL_POWER GND
J 0
(-7775 4075);
DISPLAY 0.872340 (-7775 4075);
PAINT GREEN (-7775 4075);
DISPLAY INVISIBLE (-7775 4075);
FORCEADD GND..1
(-5950 3950);
FORCEPROP 3 LASTPIN (-5950 4000) SIG_NAME GND\g
J 0
(-5940 4010);
DISPLAY 0.659574 (-5940 4010);
PAINT MONO (-5940 4010);
DISPLAY INVISIBLE (-5940 4010);
FORCEPROP 1 LAST VOLTAGE 0.0V
J 0
(-5995 3907);
DISPLAY 0.340426 (-5995 3907);
PAINT SKYBLUE (-5995 3907);
DISPLAY INVISIBLE (-5995 3907);
FORCEPROP 1 LAST SIZE 1B
J 0
(-5875 3900);
DISPLAY 0.872340 (-5875 3900);
PAINT AQUA (-5875 3900);
DISPLAY INVISIBLE (-5875 3900);
FORCEPROP 2 LAST CDS_LIB mstr_symbols
J 0
(-5950 3950);
PAINT ORANGE (-5950 3950);
DISPLAY INVISIBLE (-5950 3950);
FORCEPROP 1 LAST BODY_TYPE PLUMBING
J 0
(-5995 3907);
DISPLAY 0.340426 (-5995 3907);
PAINT GREEN (-5995 3907);
DISPLAY INVISIBLE (-5995 3907);
FORCEPROP 1 LAST PATH I64
J 0
(-5875 3950);
DISPLAY 0.872340 (-5875 3950);
PAINT AQUA (-5875 3950);
DISPLAY INVISIBLE (-5875 3950);
FORCEPROP 1 LAST HDL_POWER GND
J 0
(-5950 4100);
DISPLAY 0.872340 (-5950 4100);
PAINT GREEN (-5950 4100);
DISPLAY INVISIBLE (-5950 4100);
FORCEADD MTG_KEYHOLE..1
(-5525 4150);
FORCEPROP 1 LAST PART_NUMBER NA
J 0
(-5725 4000);
DISPLAY 0.617021 (-5725 4000);
PAINT BLUE (-5725 4000);
FORCEPROP 2 LASTPIN (-5775 4150) $PN 1
J 2
(-5785 4160);
DISPLAY 0.617021 (-5785 4160);
PAINT MONO (-5785 4160);
FORCEPROP 1 LAST LOCATION TH7A1
J 0
(-5725 4350);
DISPLAY 0.617021 (-5725 4350);
PAINT AQUA (-5725 4350);
FORCEPROP 1 LAST MATERIAL EMPTY
J 0
(-5725 4300);
DISPLAY 0.617021 (-5725 4300);
PAINT RED (-5725 4300);
FORCEPROP 1 LAST PACK_TYPE TH
J 0
(-5725 4400);
DISPLAY 0.978723 (-5725 4400);
PAINT SKYBLUE (-5725 4400);
DISPLAY INVISIBLE (-5725 4400);
FORCEPROP 0 LAST BOM_COST TEST_MFG
J 0
(-5725 4450);
DISPLAY 1.021277 (-5725 4450);
PAINT ORANGE (-5725 4450);
DISPLAY INVISIBLE (-5725 4450);
FORCEPROP 2 LAST CDS_SEC 1
J 0
(-5725 4400);
DISPLAY 1.021277 (-5725 4400);
PAINT ORANGE (-5725 4400);
DISPLAY INVISIBLE (-5725 4400);
FORCEPROP 2 LAST $SEC 1
J 0
(-5725 4400);
DISPLAY 0.680851 (-5725 4400);
PAINT MONO (-5725 4400);
DISPLAY INVISIBLE (-5725 4400);
FORCEPROP 2 LAST CDS_LOCATION TH7A1
J 0
(-5725 4350);
DISPLAY 0.617021 (-5725 4350);
PAINT AQUA (-5725 4350);
DISPLAY INVISIBLE (-5725 4350);
FORCEPROP 0 LAST ROOM MOUNTING_HOLES
J 0
(-5725 4400);
DISPLAY 1.021277 (-5725 4400);
PAINT ORANGE (-5725 4400);
DISPLAY INVISIBLE (-5725 4400);
FORCEPROP 2 LAST CDS_LIB mstr_misc
J 0
(-5525 4150);
PAINT ORANGE (-5525 4150);
DISPLAY INVISIBLE (-5525 4150);
FORCEPROP 1 LAST PATH I65
J 0
(-5525 4300);
DISPLAY 0.978723 (-5525 4300);
PAINT GREEN (-5525 4300);
DISPLAY INVISIBLE (-5525 4300);
FORCEADD GND..1
(-5025 3950);
FORCEPROP 3 LASTPIN (-5025 4000) SIG_NAME GND\g
J 0
(-5015 4010);
DISPLAY 0.659574 (-5015 4010);
PAINT MONO (-5015 4010);
DISPLAY INVISIBLE (-5015 4010);
FORCEPROP 1 LAST PATH I66
J 0
(-4950 3950);
DISPLAY 0.872340 (-4950 3950);
PAINT AQUA (-4950 3950);
DISPLAY INVISIBLE (-4950 3950);
FORCEPROP 1 LAST BODY_TYPE PLUMBING
J 0
(-5070 3907);
DISPLAY 0.340426 (-5070 3907);
PAINT GREEN (-5070 3907);
DISPLAY INVISIBLE (-5070 3907);
FORCEPROP 2 LAST CDS_LIB mstr_symbols
J 0
(-5025 3950);
PAINT ORANGE (-5025 3950);
DISPLAY INVISIBLE (-5025 3950);
FORCEPROP 1 LAST SIZE 1B
J 0
(-4950 3900);
DISPLAY 0.872340 (-4950 3900);
PAINT AQUA (-4950 3900);
DISPLAY INVISIBLE (-4950 3900);
FORCEPROP 1 LAST VOLTAGE 0.0V
J 0
(-5070 3907);
DISPLAY 0.340426 (-5070 3907);
PAINT SKYBLUE (-5070 3907);
DISPLAY INVISIBLE (-5070 3907);
FORCEPROP 1 LAST HDL_POWER GND
J 0
(-5025 4100);
DISPLAY 0.872340 (-5025 4100);
PAINT GREEN (-5025 4100);
DISPLAY INVISIBLE (-5025 4100);
FORCEADD MTG_KEYHOLE..1
(-4600 4150);
FORCEPROP 1 LAST PART_NUMBER NA
J 0
(-4800 4000);
DISPLAY 0.617021 (-4800 4000);
PAINT BLUE (-4800 4000);
FORCEPROP 2 LASTPIN (-4850 4150) $PN 1
J 2
(-4860 4160);
DISPLAY 0.617021 (-4860 4160);
PAINT MONO (-4860 4160);
FORCEPROP 1 LAST MATERIAL EMPTY
J 0
(-4800 4300);
DISPLAY 0.617021 (-4800 4300);
PAINT RED (-4800 4300);
FORCEPROP 1 LAST LOCATION TH7G1
J 0
(-4800 4350);
DISPLAY 0.617021 (-4800 4350);
PAINT AQUA (-4800 4350);
FORCEPROP 2 LAST CDS_LOCATION TH7G1
J 0
(-4800 4350);
DISPLAY 0.617021 (-4800 4350);
PAINT AQUA (-4800 4350);
DISPLAY INVISIBLE (-4800 4350);
FORCEPROP 0 LAST ROOM MOUNTING_HOLES
J 0
(-4800 4400);
DISPLAY 1.021277 (-4800 4400);
PAINT ORANGE (-4800 4400);
DISPLAY INVISIBLE (-4800 4400);
FORCEPROP 2 LAST $SEC 1
J 0
(-4800 4400);
DISPLAY 0.680851 (-4800 4400);
PAINT MONO (-4800 4400);
DISPLAY INVISIBLE (-4800 4400);
FORCEPROP 2 LAST CDS_SEC 1
J 0
(-4800 4400);
DISPLAY 1.021277 (-4800 4400);
PAINT ORANGE (-4800 4400);
DISPLAY INVISIBLE (-4800 4400);
FORCEPROP 0 LAST BOM_COST TEST_MFG
J 0
(-4800 4450);
DISPLAY 1.021277 (-4800 4450);
PAINT ORANGE (-4800 4450);
DISPLAY INVISIBLE (-4800 4450);
FORCEPROP 1 LAST PACK_TYPE TH
J 0
(-4800 4400);
DISPLAY 0.978723 (-4800 4400);
PAINT SKYBLUE (-4800 4400);
DISPLAY INVISIBLE (-4800 4400);
FORCEPROP 2 LAST CDS_LIB mstr_misc
J 0
(-4600 4150);
PAINT ORANGE (-4600 4150);
DISPLAY INVISIBLE (-4600 4150);
FORCEPROP 1 LAST PATH I67
J 0
(-4600 4300);
DISPLAY 0.978723 (-4600 4300);
PAINT GREEN (-4600 4300);
DISPLAY INVISIBLE (-4600 4300);
FORCEADD CAPTIVE_SCREW..1
(-7500 4725);
FORCEPROP 1 LAST LOCATION RM1G1
J 0
(-7755 4875);
DISPLAY 0.617021 (-7755 4875);
PAINT AQUA (-7755 4875);
FORCEPROP 1 LAST PART_NUMBER H57868-001
J 0
(-7750 4625);
DISPLAY 0.617021 (-7750 4625);
PAINT BLUE (-7750 4625);
FORCEPROP 1 LAST MATERIAL HDW
J 0
(-7755 4825);
DISPLAY 0.617021 (-7755 4825);
PAINT SKYBLUE (-7755 4825);
FORCEPROP 0 LAST ROOM MOUNTING_HOLES
J 0
(-7750 4925);
DISPLAY 1.021277 (-7750 4925);
PAINT ORANGE (-7750 4925);
DISPLAY INVISIBLE (-7750 4925);
FORCEPROP 2 LAST CDS_LOCATION RM1G1
J 0
(-7755 4875);
DISPLAY 0.617021 (-7755 4875);
PAINT AQUA (-7755 4875);
DISPLAY INVISIBLE (-7755 4875);
FORCEPROP 0 LAST BOM_COST TEST_MFG
J 0
(-7750 4975);
DISPLAY 1.021277 (-7750 4975);
PAINT ORANGE (-7750 4975);
DISPLAY INVISIBLE (-7750 4975);
FORCEPROP 1 LAST PACK_TYPE TH
J 0
(-7745 4925);
DISPLAY 0.851064 (-7745 4925);
PAINT SKYBLUE (-7745 4925);
DISPLAY INVISIBLE (-7745 4925);
FORCEPROP 1 LAST PATH I76
J 0
(-7400 4820);
DISPLAY 0.872340 (-7400 4820);
PAINT WHITE (-7400 4820);
DISPLAY INVISIBLE (-7400 4820);
FORCEPROP 2 LAST CDS_LIB mstr_misc
J 0
(-7500 4725);
PAINT ORANGE (-7500 4725);
DISPLAY INVISIBLE (-7500 4725);
FORCEADD P12V_PSU..1
(-550 2775);
FORCEPROP 3 LASTPIN (-550 2725) SIG_NAME P12V_PSU\g
J 0
(-540 2735);
DISPLAY 0.659574 (-540 2735);
PAINT MONO (-540 2735);
DISPLAY INVISIBLE (-540 2735);
FORCEPROP 1 LAST HDL_POWER P12V_PSU
J 1
(-550 2825);
DISPLAY 0.872340 (-550 2825);
PAINT GREEN (-550 2825);
DISPLAY INVISIBLE (-550 2825);
FORCEPROP 2 LAST ROOM P2V5_LAN_AUX_VR
J 0
(-550 2875);
DISPLAY 0.617021 (-550 2875);
PAINT ORANGE (-550 2875);
DISPLAY INVISIBLE (-550 2875);
FORCEPROP 1 LAST BODY_TYPE PLUMBING
J 0
(-595 2732);
DISPLAY 0.340426 (-595 2732);
PAINT GREEN (-595 2732);
DISPLAY INVISIBLE (-595 2732);
FORCEPROP 2 LAST CDS_LIB mstr_symbols
J 0
(-550 2775);
PAINT ORANGE (-550 2775);
DISPLAY INVISIBLE (-550 2775);
FORCEPROP 2 LAST BOM_COST NT_BASE_VRD
J 0
(-550 2875);
DISPLAY 0.617021 (-550 2875);
PAINT ORANGE (-550 2875);
DISPLAY INVISIBLE (-550 2875);
FORCEPROP 1 LAST VOLTAGE 12.0
J 0
(-595 2732);
DISPLAY 0.340426 (-595 2732);
PAINT SKYBLUE (-595 2732);
DISPLAY INVISIBLE (-595 2732);
FORCEPROP 1 LAST PATH I77
J 0
(-500 2800);
DISPLAY 0.872340 (-500 2800);
PAINT AQUA (-500 2800);
DISPLAY INVISIBLE (-500 2800);
FORCEADD CONN12_G98257001..1
(-1250 2275);
FORCEPROP 1 LAST PART_NUMBER G98257-001
J 0
(-1450 1975);
DISPLAY 0.617021 (-1450 1975);
PAINT BLUE (-1450 1975);
FORCEPROP 2 LASTPIN (-1500 2375) $PN B1
J 2
(-1510 2385);
DISPLAY 0.617021 (-1510 2385);
PAINT ORANGE (-1510 2385);
FORCEPROP 2 LASTPIN (-1500 2325) $PN B2
J 2
(-1510 2335);
DISPLAY 0.617021 (-1510 2335);
PAINT ORANGE (-1510 2335);
FORCEPROP 2 LASTPIN (-1500 2275) $PN B3
J 2
(-1510 2285);
DISPLAY 0.617021 (-1510 2285);
PAINT ORANGE (-1510 2285);
FORCEPROP 2 LASTPIN (-1500 2175) $PN C1
J 2
(-1510 2185);
DISPLAY 0.617021 (-1510 2185);
PAINT ORANGE (-1510 2185);
FORCEPROP 2 LASTPIN (-1500 2125) $PN C2
J 2
(-1510 2135);
DISPLAY 0.617021 (-1510 2135);
PAINT ORANGE (-1510 2135);
FORCEPROP 2 LASTPIN (-1500 2075) $PN C3
J 2
(-1510 2085);
DISPLAY 0.617021 (-1510 2085);
PAINT ORANGE (-1510 2085);
FORCEPROP 1 LAST MATERIAL CONN
J 0
(-1450 2550);
DISPLAY 0.617021 (-1450 2550);
PAINT SKYBLUE (-1450 2550);
FORCEPROP 1 LAST LOCATION J1D1
J 0
(-1450 2600);
DISPLAY 0.617021 (-1450 2600);
PAINT AQUA (-1450 2600);
FORCEPROP 2 LASTPIN (-1000 2075) $PN D3
J 0
(-990 2085);
DISPLAY 0.617021 (-990 2085);
PAINT ORANGE (-990 2085);
FORCEPROP 2 LASTPIN (-1000 2125) $PN D2
J 0
(-990 2135);
DISPLAY 0.617021 (-990 2135);
PAINT ORANGE (-990 2135);
FORCEPROP 2 LASTPIN (-1000 2175) $PN D1
J 0
(-990 2185);
DISPLAY 0.617021 (-990 2185);
PAINT ORANGE (-990 2185);
FORCEPROP 2 LASTPIN (-1000 2275) $PN A3
J 0
(-990 2285);
DISPLAY 0.617021 (-990 2285);
PAINT ORANGE (-990 2285);
FORCEPROP 2 LASTPIN (-1000 2325) $PN A2
J 0
(-990 2335);
DISPLAY 0.617021 (-990 2335);
PAINT ORANGE (-990 2335);
FORCEPROP 2 LASTPIN (-1000 2375) $PN A1
J 0
(-990 2385);
DISPLAY 0.617021 (-990 2385);
PAINT ORANGE (-990 2385);
FORCEPROP 2 LAST CDS_LIB mstr_conn
J 0
(-1250 2275);
PAINT ORANGE (-1250 2275);
DISPLAY INVISIBLE (-1250 2275);
FORCEPROP 1 LAST CDS_LMAN_SYM_OUTLINE -200,250,200,-250
J 0
(-1250 2275);
DISPLAY 0.468085 (-1250 2275);
PAINT GREEN (-1250 2275);
DISPLAY INVISIBLE (-1250 2275);
FORCEPROP 1 LAST PATH I78
J 0
(-1150 2551);
PAINT GREEN (-1150 2551);
DISPLAY INVISIBLE (-1150 2551);
FORCEPROP 0 LAST ROOM HOT_SWAP
J 0
(-1500 2725);
DISPLAY 1.021277 (-1500 2725);
PAINT ORANGE (-1500 2725);
DISPLAY INVISIBLE (-1500 2725);
FORCEPROP 2 LAST CDS_LOCATION J1D1
J 0
(-1450 2600);
DISPLAY 0.617021 (-1450 2600);
PAINT AQUA (-1450 2600);
DISPLAY INVISIBLE (-1450 2600);
FORCEPROP 2 LAST SEC 1
J 0
(-1450 2650);
DISPLAY 0.680851 (-1450 2650);
PAINT MONO (-1450 2650);
DISPLAY INVISIBLE (-1450 2650);
FORCEPROP 1 LAST PACK_TYPE THMT
J 0
(-1450 2650);
PAINT SKYBLUE (-1450 2650);
DISPLAY INVISIBLE (-1450 2650);
FORCEPROP 2 LAST SEC_TYPE THMT
J 0
(-1450 2650);
DISPLAY 1.021277 (-1450 2650);
PAINT ORANGE (-1450 2650);
DISPLAY INVISIBLE (-1450 2650);
FORCEADD GND..1
(-675 1925);
FORCEPROP 3 LASTPIN (-675 1975) SIG_NAME GND\g
J 0
(-665 1985);
DISPLAY 0.659574 (-665 1985);
PAINT MONO (-665 1985);
DISPLAY INVISIBLE (-665 1985);
FORCEPROP 1 LAST VOLTAGE 0.0V
J 0
(-720 1882);
DISPLAY 0.340426 (-720 1882);
PAINT SKYBLUE (-720 1882);
DISPLAY INVISIBLE (-720 1882);
FORCEPROP 1 LAST SIZE 1B
J 0
(-600 1875);
DISPLAY 0.872340 (-600 1875);
PAINT AQUA (-600 1875);
DISPLAY INVISIBLE (-600 1875);
FORCEPROP 2 LAST CDS_LIB mstr_symbols
J 0
(-675 1925);
PAINT ORANGE (-675 1925);
DISPLAY INVISIBLE (-675 1925);
FORCEPROP 1 LAST BODY_TYPE PLUMBING
J 0
(-720 1882);
DISPLAY 0.340426 (-720 1882);
PAINT GREEN (-720 1882);
DISPLAY INVISIBLE (-720 1882);
FORCEPROP 1 LAST PATH I79
J 0
(-600 1925);
DISPLAY 0.872340 (-600 1925);
PAINT AQUA (-600 1925);
DISPLAY INVISIBLE (-600 1925);
FORCEPROP 1 LAST HDL_POWER GND
J 0
(-675 2075);
DISPLAY 0.872340 (-675 2075);
PAINT GREEN (-675 2075);
DISPLAY INVISIBLE (-675 2075);
FORCEADD P12V_PSU..1
(-1925 2775);
FORCEPROP 3 LASTPIN (-1925 2725) SIG_NAME P12V_PSU\g
J 0
(-1915 2735);
DISPLAY 0.659574 (-1915 2735);
PAINT MONO (-1915 2735);
DISPLAY INVISIBLE (-1915 2735);
FORCEPROP 1 LAST HDL_POWER P12V_PSU
J 1
(-1925 2825);
DISPLAY 0.872340 (-1925 2825);
PAINT GREEN (-1925 2825);
DISPLAY INVISIBLE (-1925 2825);
FORCEPROP 1 LAST VOLTAGE 12.0
J 0
(-1970 2732);
DISPLAY 0.340426 (-1970 2732);
PAINT SKYBLUE (-1970 2732);
DISPLAY INVISIBLE (-1970 2732);
FORCEPROP 2 LAST CDS_LIB mstr_symbols
J 0
(-1925 2775);
PAINT ORANGE (-1925 2775);
DISPLAY INVISIBLE (-1925 2775);
FORCEPROP 2 LAST BOM_COST NT_BASE_VRD
J 0
(-1925 2875);
DISPLAY 0.617021 (-1925 2875);
PAINT ORANGE (-1925 2875);
DISPLAY INVISIBLE (-1925 2875);
FORCEPROP 1 LAST BODY_TYPE PLUMBING
J 0
(-1970 2732);
DISPLAY 0.340426 (-1970 2732);
PAINT GREEN (-1970 2732);
DISPLAY INVISIBLE (-1970 2732);
FORCEPROP 1 LAST PATH I80
J 0
(-1875 2800);
DISPLAY 0.872340 (-1875 2800);
PAINT AQUA (-1875 2800);
DISPLAY INVISIBLE (-1875 2800);
FORCEPROP 2 LAST ROOM P2V5_LAN_AUX_VR
J 0
(-1925 2875);
DISPLAY 0.617021 (-1925 2875);
PAINT ORANGE (-1925 2875);
DISPLAY INVISIBLE (-1925 2875);
FORCEADD GND..1
(-1775 1925);
FORCEPROP 3 LASTPIN (-1775 1975) SIG_NAME GND\g
J 0
(-1765 1985);
DISPLAY 0.659574 (-1765 1985);
PAINT MONO (-1765 1985);
DISPLAY INVISIBLE (-1765 1985);
FORCEPROP 1 LAST PATH I81
J 0
(-1700 1925);
DISPLAY 0.872340 (-1700 1925);
PAINT AQUA (-1700 1925);
DISPLAY INVISIBLE (-1700 1925);
FORCEPROP 1 LAST BODY_TYPE PLUMBING
J 0
(-1820 1882);
DISPLAY 0.340426 (-1820 1882);
PAINT GREEN (-1820 1882);
DISPLAY INVISIBLE (-1820 1882);
FORCEPROP 1 LAST VOLTAGE 0.0V
J 0
(-1820 1882);
DISPLAY 0.340426 (-1820 1882);
PAINT SKYBLUE (-1820 1882);
DISPLAY INVISIBLE (-1820 1882);
FORCEPROP 2 LAST CDS_LIB mstr_symbols
J 0
(-1775 1925);
PAINT ORANGE (-1775 1925);
DISPLAY INVISIBLE (-1775 1925);
FORCEPROP 1 LAST SIZE 1B
J 0
(-1700 1875);
DISPLAY 0.872340 (-1700 1875);
PAINT AQUA (-1700 1875);
DISPLAY INVISIBLE (-1700 1875);
FORCEPROP 1 LAST HDL_POWER GND
J 0
(-1775 2075);
DISPLAY 0.872340 (-1775 2075);
PAINT GREEN (-1775 2075);
DISPLAY INVISIBLE (-1775 2075);
FORCEADD CAPP..1
(-7175 2950);
FORCEPROP 1 LASTPIN (-7175 3050) $PN 1
J 0
(-7165 3035);
DISPLAY 0.617021 (-7165 3035);
PAINT ORANGE (-7165 3035);
FORCEPROP 1 LASTPIN (-7175 2850) $PN 2
J 0
(-7165 2835);
DISPLAY 0.617021 (-7165 2835);
PAINT ORANGE (-7165 2835);
FORCEPROP 1 LAST MATERIAL ALUM
J 0
(-7125 2850);
DISPLAY 0.617021 (-7125 2850);
PAINT SKYBLUE (-7125 2850);
FORCEPROP 1 LAST VOLTAGE 16V
J 0
(-7125 2900);
DISPLAY 0.617021 (-7125 2900);
PAINT SKYBLUE (-7125 2900);
FORCEPROP 1 LAST PACK_TYPE 4040LF
J 0
(-7125 2800);
DISPLAY 0.617021 (-7125 2800);
PAINT SKYBLUE (-7125 2800);
FORCEPROP 1 LAST TOLERANCE 20%
J 0
(-7125 2950);
DISPLAY 0.617021 (-7125 2950);
PAINT SKYBLUE (-7125 2950);
FORCEPROP 1 LAST VALUE 470UF
J 0
(-7125 3000);
DISPLAY 0.617021 (-7125 3000);
PAINT SKYBLUE (-7125 3000);
FORCEPROP 1 LAST PART_NUMBER A93539-036
J 0
(-7125 2750);
DISPLAY 0.617021 (-7125 2750);
PAINT BLUE (-7125 2750);
FORCEPROP 1 LAST LOCATION C4F6
J 0
(-7125 3050);
DISPLAY 0.617021 (-7125 3050);
PAINT AQUA (-7125 3050);
FORCEPROP 2 LAST CDS_LIB mstr_discrete
J 0
(-7175 2950);
PAINT MONO (-7175 2950);
DISPLAY INVISIBLE (-7175 2950);
FORCEPROP 2 LAST CDS_LOCATION C4F6
J 0
(-7125 3050);
DISPLAY 0.617021 (-7125 3050);
PAINT AQUA (-7125 3050);
DISPLAY INVISIBLE (-7125 3050);
FORCEPROP 2 LAST CDS_SEC 1
J 0
(-7125 3150);
PAINT MONO (-7125 3150);
DISPLAY INVISIBLE (-7125 3150);
FORCEPROP 2 LAST $SEC 1
J 0
(-7125 3150);
PAINT MONO (-7125 3150);
DISPLAY INVISIBLE (-7125 3150);
FORCEPROP 1 LAST PATH I82
J 0
(-7125 3100);
DISPLAY 0.978723 (-7125 3100);
PAINT ORANGE (-7125 3100);
DISPLAY INVISIBLE (-7125 3100);
FORCEADD CAPP..1
(-6675 2950);
FORCEPROP 1 LASTPIN (-6675 3050) $PN 1
J 0
(-6665 3035);
DISPLAY 0.617021 (-6665 3035);
PAINT ORANGE (-6665 3035);
FORCEPROP 1 LASTPIN (-6675 2850) $PN 2
J 0
(-6665 2835);
DISPLAY 0.617021 (-6665 2835);
PAINT ORANGE (-6665 2835);
FORCEPROP 1 LAST MATERIAL ALUM
J 0
(-6625 2850);
DISPLAY 0.617021 (-6625 2850);
PAINT SKYBLUE (-6625 2850);
FORCEPROP 1 LAST VOLTAGE 16V
J 0
(-6625 2900);
DISPLAY 0.617021 (-6625 2900);
PAINT SKYBLUE (-6625 2900);
FORCEPROP 1 LAST PACK_TYPE 4040LF
J 0
(-6625 2800);
DISPLAY 0.617021 (-6625 2800);
PAINT SKYBLUE (-6625 2800);
FORCEPROP 1 LAST TOLERANCE 20%
J 0
(-6625 2950);
DISPLAY 0.617021 (-6625 2950);
PAINT SKYBLUE (-6625 2950);
FORCEPROP 1 LAST VALUE 470UF
J 0
(-6625 3000);
DISPLAY 0.617021 (-6625 3000);
PAINT SKYBLUE (-6625 3000);
FORCEPROP 1 LAST PART_NUMBER A93539-036
J 0
(-6625 2750);
DISPLAY 0.617021 (-6625 2750);
PAINT BLUE (-6625 2750);
FORCEPROP 1 LAST LOCATION C4B13
J 0
(-6625 3050);
DISPLAY 0.617021 (-6625 3050);
PAINT AQUA (-6625 3050);
FORCEPROP 2 LAST CDS_LIB mstr_discrete
J 0
(-6675 2950);
PAINT MONO (-6675 2950);
DISPLAY INVISIBLE (-6675 2950);
FORCEPROP 2 LAST CDS_LOCATION C4B13
J 0
(-6625 3050);
DISPLAY 0.617021 (-6625 3050);
PAINT AQUA (-6625 3050);
DISPLAY INVISIBLE (-6625 3050);
FORCEPROP 2 LAST CDS_SEC 1
J 0
(-6625 3150);
PAINT MONO (-6625 3150);
DISPLAY INVISIBLE (-6625 3150);
FORCEPROP 2 LAST $SEC 1
J 0
(-6625 3150);
PAINT MONO (-6625 3150);
DISPLAY INVISIBLE (-6625 3150);
FORCEPROP 1 LAST PATH I83
J 0
(-6625 3100);
DISPLAY 0.978723 (-6625 3100);
PAINT ORANGE (-6625 3100);
DISPLAY INVISIBLE (-6625 3100);
FORCEADD CAPP..1
(-6150 2925);
FORCEPROP 1 LASTPIN (-6150 3025) $PN 1
J 0
(-6140 3010);
DISPLAY 0.617021 (-6140 3010);
PAINT ORANGE (-6140 3010);
FORCEPROP 1 LASTPIN (-6150 2825) $PN 2
J 0
(-6140 2810);
DISPLAY 0.617021 (-6140 2810);
PAINT ORANGE (-6140 2810);
FORCEPROP 1 LAST VOLTAGE 16V
J 0
(-6100 2875);
DISPLAY 0.617021 (-6100 2875);
PAINT SKYBLUE (-6100 2875);
FORCEPROP 1 LAST PACK_TYPE 4040LF
J 0
(-6100 2775);
DISPLAY 0.617021 (-6100 2775);
PAINT SKYBLUE (-6100 2775);
FORCEPROP 1 LAST TOLERANCE 20%
J 0
(-6100 2925);
DISPLAY 0.617021 (-6100 2925);
PAINT SKYBLUE (-6100 2925);
FORCEPROP 1 LAST VALUE 470UF
J 0
(-6100 2975);
DISPLAY 0.617021 (-6100 2975);
PAINT SKYBLUE (-6100 2975);
FORCEPROP 1 LAST LOCATION C1B14
J 0
(-6100 3025);
DISPLAY 0.617021 (-6100 3025);
PAINT AQUA (-6100 3025);
FORCEPROP 1 LAST PART_NUMBER A93539-036
J 0
(-6100 2725);
DISPLAY 0.617021 (-6100 2725);
PAINT BLUE (-6100 2725);
FORCEPROP 1 LAST MATERIAL ALUM
J 0
(-6100 2825);
DISPLAY 0.617021 (-6100 2825);
PAINT SKYBLUE (-6100 2825);
FORCEPROP 2 LAST CDS_LIB mstr_discrete
J 0
(-6150 2925);
PAINT MONO (-6150 2925);
DISPLAY INVISIBLE (-6150 2925);
FORCEPROP 2 LAST CDS_LOCATION C1B14
J 0
(-6100 3025);
DISPLAY 0.617021 (-6100 3025);
PAINT AQUA (-6100 3025);
DISPLAY INVISIBLE (-6100 3025);
FORCEPROP 2 LAST CDS_SEC 1
J 0
(-6100 3125);
PAINT MONO (-6100 3125);
DISPLAY INVISIBLE (-6100 3125);
FORCEPROP 2 LAST $SEC 1
J 0
(-6100 3125);
PAINT MONO (-6100 3125);
DISPLAY INVISIBLE (-6100 3125);
FORCEPROP 1 LAST PATH I84
J 0
(-6100 3075);
DISPLAY 0.978723 (-6100 3075);
PAINT ORANGE (-6100 3075);
DISPLAY INVISIBLE (-6100 3075);
FORCEADD CAPP..1
(-5650 2900);
FORCEPROP 1 LASTPIN (-5650 3000) $PN 1
J 0
(-5640 2985);
DISPLAY 0.617021 (-5640 2985);
PAINT ORANGE (-5640 2985);
FORCEPROP 1 LASTPIN (-5650 2800) $PN 2
J 0
(-5640 2785);
DISPLAY 0.617021 (-5640 2785);
PAINT ORANGE (-5640 2785);
FORCEPROP 1 LAST LOCATION C1F7
J 0
(-5600 3000);
DISPLAY 0.617021 (-5600 3000);
PAINT AQUA (-5600 3000);
FORCEPROP 1 LAST PART_NUMBER A93539-036
J 0
(-5600 2700);
DISPLAY 0.617021 (-5600 2700);
PAINT BLUE (-5600 2700);
FORCEPROP 1 LAST VALUE 470UF
J 0
(-5600 2950);
DISPLAY 0.617021 (-5600 2950);
PAINT SKYBLUE (-5600 2950);
FORCEPROP 1 LAST TOLERANCE 20%
J 0
(-5600 2900);
DISPLAY 0.617021 (-5600 2900);
PAINT SKYBLUE (-5600 2900);
FORCEPROP 1 LAST PACK_TYPE 4040LF
J 0
(-5600 2750);
DISPLAY 0.617021 (-5600 2750);
PAINT SKYBLUE (-5600 2750);
FORCEPROP 1 LAST VOLTAGE 16V
J 0
(-5600 2850);
DISPLAY 0.617021 (-5600 2850);
PAINT SKYBLUE (-5600 2850);
FORCEPROP 1 LAST MATERIAL ALUM
J 0
(-5600 2800);
DISPLAY 0.617021 (-5600 2800);
PAINT SKYBLUE (-5600 2800);
FORCEPROP 2 LAST CDS_LIB mstr_discrete
J 0
(-5650 2900);
PAINT MONO (-5650 2900);
DISPLAY INVISIBLE (-5650 2900);
FORCEPROP 2 LAST CDS_LOCATION C1F7
J 0
(-5600 3000);
DISPLAY 0.617021 (-5600 3000);
PAINT AQUA (-5600 3000);
DISPLAY INVISIBLE (-5600 3000);
FORCEPROP 1 LAST PATH I85
J 0
(-5600 3050);
DISPLAY 0.978723 (-5600 3050);
PAINT ORANGE (-5600 3050);
DISPLAY INVISIBLE (-5600 3050);
FORCEPROP 2 LAST $SEC 1
J 0
(-5600 3100);
PAINT MONO (-5600 3100);
DISPLAY INVISIBLE (-5600 3100);
FORCEPROP 2 LAST CDS_SEC 1
J 0
(-5600 3100);
PAINT MONO (-5600 3100);
DISPLAY INVISIBLE (-5600 3100);
FORCEADD P12V_STBY..1
(-6250 3375);
FORCEPROP 3 LASTPIN (-6250 3325) SIG_NAME P12V_STBY\g
J 0
(-6240 3335);
DISPLAY 0.659574 (-6240 3335);
PAINT MONO (-6240 3335);
DISPLAY INVISIBLE (-6240 3335);
FORCEPROP 1 LAST HDL_POWER P12V_STBY
J 0
(-6550 3250);
DISPLAY 0.872340 (-6550 3250);
PAINT ORANGE (-6550 3250);
DISPLAY INVISIBLE (-6550 3250);
FORCEPROP 1 LAST PATH I92
J 0
(-6205 3377);
DISPLAY 0.340426 (-6205 3377);
PAINT GREEN (-6205 3377);
DISPLAY INVISIBLE (-6205 3377);
FORCEPROP 1 LAST BODY_TYPE PLUMBING
J 0
(-6295 3332);
DISPLAY 0.340426 (-6295 3332);
PAINT GREEN (-6295 3332);
DISPLAY INVISIBLE (-6295 3332);
FORCEPROP 1 LAST SIZE 1B
J 0
(-6205 3397);
DISPLAY 0.340426 (-6205 3397);
PAINT GREEN (-6205 3397);
DISPLAY INVISIBLE (-6205 3397);
FORCEPROP 2 LAST CDS_LIB mstr_symbols
J 0
(-6250 3375);
PAINT MONO (-6250 3375);
DISPLAY INVISIBLE (-6250 3375);
FORCEPROP 1 LAST VOLTAGE 12.0V
J 0
(-6295 3332);
DISPLAY 0.340426 (-6295 3332);
PAINT SKYBLUE (-6295 3332);
DISPLAY INVISIBLE (-6295 3332);
FORCEADD P12V_STBY..1
(-6400 1150);
FORCEPROP 3 LASTPIN (-6400 1100) SIG_NAME P12V_STBY\g
J 0
(-6390 1110);
DISPLAY 0.659574 (-6390 1110);
PAINT MONO (-6390 1110);
DISPLAY INVISIBLE (-6390 1110);
FORCEPROP 1 LAST HDL_POWER P12V_STBY
J 0
(-6700 1025);
DISPLAY 0.872340 (-6700 1025);
PAINT ORANGE (-6700 1025);
DISPLAY INVISIBLE (-6700 1025);
FORCEPROP 1 LAST BODY_TYPE PLUMBING
J 0
(-6445 1107);
DISPLAY 0.340426 (-6445 1107);
PAINT GREEN (-6445 1107);
DISPLAY INVISIBLE (-6445 1107);
FORCEPROP 1 LAST VOLTAGE 12.0V
J 0
(-6445 1107);
DISPLAY 0.340426 (-6445 1107);
PAINT SKYBLUE (-6445 1107);
DISPLAY INVISIBLE (-6445 1107);
FORCEPROP 2 LAST CDS_LIB mstr_symbols
J 0
(-6400 1150);
PAINT MONO (-6400 1150);
DISPLAY INVISIBLE (-6400 1150);
FORCEPROP 1 LAST SIZE 1B
J 0
(-6355 1172);
DISPLAY 0.340426 (-6355 1172);
PAINT GREEN (-6355 1172);
DISPLAY INVISIBLE (-6355 1172);
FORCEPROP 1 LAST PATH I93
J 0
(-6355 1152);
DISPLAY 0.340426 (-6355 1152);
PAINT GREEN (-6355 1152);
DISPLAY INVISIBLE (-6355 1152);
FORCEADD GND..1
(-6400 325);
FORCEPROP 3 LASTPIN (-6400 375) SIG_NAME GND\g
J 0
(-6390 385);
DISPLAY 0.659574 (-6390 385);
PAINT MONO (-6390 385);
DISPLAY INVISIBLE (-6390 385);
FORCEPROP 1 LAST VOLTAGE 0.0V
J 0
(-6445 282);
DISPLAY 0.340426 (-6445 282);
PAINT SKYBLUE (-6445 282);
DISPLAY INVISIBLE (-6445 282);
FORCEPROP 1 LAST BODY_TYPE PLUMBING
J 0
(-6445 282);
DISPLAY 0.340426 (-6445 282);
PAINT GREEN (-6445 282);
DISPLAY INVISIBLE (-6445 282);
FORCEPROP 2 LAST CDS_LIB mstr_symbols
J 0
(-6400 325);
PAINT MONO (-6400 325);
DISPLAY INVISIBLE (-6400 325);
FORCEPROP 1 LAST HDL_POWER GND
J 0
(-6400 475);
DISPLAY 0.872340 (-6400 475);
PAINT GREEN (-6400 475);
DISPLAY INVISIBLE (-6400 475);
FORCEPROP 1 LAST SIZE 1B
J 0
(-6325 275);
DISPLAY 0.872340 (-6325 275);
PAINT AQUA (-6325 275);
DISPLAY INVISIBLE (-6325 275);
FORCEPROP 1 LAST PATH I94
J 0
(-6325 325);
DISPLAY 0.872340 (-6325 325);
PAINT AQUA (-6325 325);
DISPLAY INVISIBLE (-6325 325);
FORCEADD GND..1
(-6375 2550);
FORCEPROP 3 LASTPIN (-6375 2600) SIG_NAME GND\g
J 0
(-6365 2610);
DISPLAY 0.659574 (-6365 2610);
PAINT MONO (-6365 2610);
DISPLAY INVISIBLE (-6365 2610);
FORCEPROP 1 LAST BODY_TYPE PLUMBING
J 0
(-6420 2507);
DISPLAY 0.340426 (-6420 2507);
PAINT GREEN (-6420 2507);
DISPLAY INVISIBLE (-6420 2507);
FORCEPROP 1 LAST VOLTAGE 0.0V
J 0
(-6420 2507);
DISPLAY 0.340426 (-6420 2507);
PAINT SKYBLUE (-6420 2507);
DISPLAY INVISIBLE (-6420 2507);
FORCEPROP 1 LAST SIZE 1B
J 0
(-6300 2500);
DISPLAY 0.872340 (-6300 2500);
PAINT AQUA (-6300 2500);
DISPLAY INVISIBLE (-6300 2500);
FORCEPROP 1 LAST PATH I95
J 0
(-6300 2550);
DISPLAY 0.872340 (-6300 2550);
PAINT AQUA (-6300 2550);
DISPLAY INVISIBLE (-6300 2550);
FORCEPROP 2 LAST CDS_LIB mstr_symbols
J 0
(-6375 2550);
PAINT MONO (-6375 2550);
DISPLAY INVISIBLE (-6375 2550);
FORCEPROP 1 LAST HDL_POWER GND
J 0
(-6375 2700);
DISPLAY 0.872340 (-6375 2700);
PAINT GREEN (-6375 2700);
DISPLAY INVISIBLE (-6375 2700);
FORCEADD CAPP..1
(-7275 775);
FORCEPROP 1 LAST MATERIAL TANT
J 0
(-7225 675);
DISPLAY 0.617021 (-7225 675);
PAINT SKYBLUE (-7225 675);
FORCEPROP 1 LAST VOLTAGE 16V
J 0
(-7225 725);
DISPLAY 0.617021 (-7225 725);
PAINT SKYBLUE (-7225 725);
FORCEPROP 1 LAST PACK_TYPE 3018
J 0
(-7225 625);
DISPLAY 0.617021 (-7225 625);
PAINT SKYBLUE (-7225 625);
FORCEPROP 1 LAST TOLERANCE 20%
J 0
(-7225 775);
DISPLAY 0.617021 (-7225 775);
PAINT SKYBLUE (-7225 775);
FORCEPROP 1 LAST VALUE 68UF
J 0
(-7225 825);
DISPLAY 0.617021 (-7225 825);
PAINT SKYBLUE (-7225 825);
FORCEPROP 1 LAST PART_NUMBER 724613-112
J 0
(-7225 575);
DISPLAY 0.617021 (-7225 575);
PAINT BLUE (-7225 575);
FORCEPROP 1 LAST LOCATION C4F5
J 0
(-7225 875);
DISPLAY 0.617021 (-7225 875);
PAINT AQUA (-7225 875);
FORCEPROP 1 LASTPIN (-7275 675) $PN 2
J 0
(-7265 660);
DISPLAY 0.787234 (-7265 660);
PAINT ORANGE (-7265 660);
DISPLAY INVISIBLE (-7265 660);
FORCEPROP 2 LAST CDS_LIB mstr_discrete
J 0
(-7275 775);
PAINT MONO (-7275 775);
DISPLAY INVISIBLE (-7275 775);
FORCEPROP 2 LAST CDS_SEC 1
J 0
(-7225 975);
PAINT MONO (-7225 975);
DISPLAY INVISIBLE (-7225 975);
FORCEPROP 2 LAST $SEC 1
J 0
(-7225 975);
PAINT MONO (-7225 975);
DISPLAY INVISIBLE (-7225 975);
FORCEPROP 2 LAST CDS_LOCATION C4F5
J 0
(-7225 875);
DISPLAY 0.617021 (-7225 875);
PAINT AQUA (-7225 875);
DISPLAY INVISIBLE (-7225 875);
FORCEPROP 1 LAST PATH I96
J 0
(-7225 925);
DISPLAY 0.978723 (-7225 925);
PAINT ORANGE (-7225 925);
DISPLAY INVISIBLE (-7225 925);
FORCEPROP 1 LASTPIN (-7275 875) $PN 1
J 0
(-7265 860);
DISPLAY 0.787234 (-7265 860);
PAINT ORANGE (-7265 860);
DISPLAY INVISIBLE (-7265 860);
FORCEADD CAPP..1
(-6900 775);
FORCEPROP 1 LAST PACK_TYPE 3018
J 0
(-6850 625);
DISPLAY 0.617021 (-6850 625);
PAINT SKYBLUE (-6850 625);
FORCEPROP 1 LAST VOLTAGE 16V
J 0
(-6850 725);
DISPLAY 0.617021 (-6850 725);
PAINT SKYBLUE (-6850 725);
FORCEPROP 1 LAST MATERIAL TANT
J 0
(-6850 675);
DISPLAY 0.617021 (-6850 675);
PAINT SKYBLUE (-6850 675);
FORCEPROP 1 LAST VALUE 68UF
J 0
(-6850 825);
DISPLAY 0.617021 (-6850 825);
PAINT SKYBLUE (-6850 825);
FORCEPROP 1 LAST LOCATION C4B14
J 0
(-6850 875);
DISPLAY 0.617021 (-6850 875);
PAINT AQUA (-6850 875);
FORCEPROP 1 LAST TOLERANCE 20%
J 0
(-6850 775);
DISPLAY 0.617021 (-6850 775);
PAINT SKYBLUE (-6850 775);
FORCEPROP 1 LAST PART_NUMBER 724613-112
J 0
(-6850 575);
DISPLAY 0.617021 (-6850 575);
PAINT BLUE (-6850 575);
FORCEPROP 1 LASTPIN (-6900 675) $PN 2
J 0
(-6890 660);
DISPLAY 0.787234 (-6890 660);
PAINT ORANGE (-6890 660);
DISPLAY INVISIBLE (-6890 660);
FORCEPROP 2 LAST CDS_LIB mstr_discrete
J 0
(-6900 775);
PAINT MONO (-6900 775);
DISPLAY INVISIBLE (-6900 775);
FORCEPROP 2 LAST CDS_SEC 1
J 0
(-6850 975);
PAINT MONO (-6850 975);
DISPLAY INVISIBLE (-6850 975);
FORCEPROP 2 LAST $SEC 1
J 0
(-6850 975);
PAINT MONO (-6850 975);
DISPLAY INVISIBLE (-6850 975);
FORCEPROP 2 LAST CDS_LOCATION C4B14
J 0
(-6850 875);
DISPLAY 0.617021 (-6850 875);
PAINT AQUA (-6850 875);
DISPLAY INVISIBLE (-6850 875);
FORCEPROP 1 LASTPIN (-6900 875) $PN 1
J 0
(-6890 860);
DISPLAY 0.787234 (-6890 860);
PAINT ORANGE (-6890 860);
DISPLAY INVISIBLE (-6890 860);
FORCEPROP 1 LAST PATH I97
J 0
(-6850 925);
DISPLAY 0.978723 (-6850 925);
PAINT ORANGE (-6850 925);
DISPLAY INVISIBLE (-6850 925);
FORCEADD CAPP..1
(-5300 750);
FORCEPROP 1 LAST MATERIAL TANT
J 0
(-5250 650);
DISPLAY 0.617021 (-5250 650);
PAINT SKYBLUE (-5250 650);
FORCEPROP 1 LAST VOLTAGE 16V
J 0
(-5250 700);
DISPLAY 0.617021 (-5250 700);
PAINT SKYBLUE (-5250 700);
FORCEPROP 1 LAST PACK_TYPE 3018
J 0
(-5250 600);
DISPLAY 0.617021 (-5250 600);
PAINT SKYBLUE (-5250 600);
FORCEPROP 1 LAST TOLERANCE 20%
J 0
(-5250 750);
DISPLAY 0.617021 (-5250 750);
PAINT SKYBLUE (-5250 750);
FORCEPROP 1 LAST VALUE 68UF
J 0
(-5250 800);
DISPLAY 0.617021 (-5250 800);
PAINT SKYBLUE (-5250 800);
FORCEPROP 1 LAST LOCATION C3T6
J 0
(-5250 850);
DISPLAY 0.617021 (-5250 850);
PAINT AQUA (-5250 850);
FORCEPROP 1 LAST PART_NUMBER 724613-112
J 0
(-5250 550);
DISPLAY 0.617021 (-5250 550);
PAINT BLUE (-5250 550);
FORCEPROP 1 LASTPIN (-5300 650) $PN 2
J 0
(-5290 635);
DISPLAY 0.787234 (-5290 635);
PAINT ORANGE (-5290 635);
DISPLAY INVISIBLE (-5290 635);
FORCEPROP 2 LAST CDS_LIB mstr_discrete
J 0
(-5300 750);
PAINT MONO (-5300 750);
DISPLAY INVISIBLE (-5300 750);
FORCEPROP 1 LASTPIN (-5300 850) $PN 1
J 0
(-5290 835);
DISPLAY 0.787234 (-5290 835);
PAINT ORANGE (-5290 835);
DISPLAY INVISIBLE (-5290 835);
FORCEPROP 1 LAST PATH I98
J 0
(-5250 900);
DISPLAY 0.978723 (-5250 900);
PAINT ORANGE (-5250 900);
DISPLAY INVISIBLE (-5250 900);
FORCEPROP 2 LAST CDS_LOCATION C3T6
J 0
(-5250 850);
DISPLAY 0.617021 (-5250 850);
PAINT AQUA (-5250 850);
DISPLAY INVISIBLE (-5250 850);
FORCEPROP 2 LAST $SEC 1
J 0
(-5250 950);
PAINT MONO (-5250 950);
DISPLAY INVISIBLE (-5250 950);
FORCEPROP 2 LAST CDS_SEC 1
J 0
(-5250 950);
PAINT MONO (-5250 950);
DISPLAY INVISIBLE (-5250 950);
FORCEADD CAPP..1
(-5750 775);
FORCEPROP 1 LAST MATERIAL TANT
J 0
(-5700 675);
DISPLAY 0.617021 (-5700 675);
PAINT SKYBLUE (-5700 675);
FORCEPROP 1 LAST VOLTAGE 16V
J 0
(-5700 725);
DISPLAY 0.617021 (-5700 725);
PAINT SKYBLUE (-5700 725);
FORCEPROP 1 LAST PACK_TYPE 3018
J 0
(-5700 625);
DISPLAY 0.617021 (-5700 625);
PAINT SKYBLUE (-5700 625);
FORCEPROP 1 LAST TOLERANCE 20%
J 0
(-5700 775);
DISPLAY 0.617021 (-5700 775);
PAINT SKYBLUE (-5700 775);
FORCEPROP 1 LAST VALUE 68UF
J 0
(-5700 825);
DISPLAY 0.617021 (-5700 825);
PAINT SKYBLUE (-5700 825);
FORCEPROP 1 LAST PART_NUMBER 724613-112
J 0
(-5700 575);
DISPLAY 0.617021 (-5700 575);
PAINT BLUE (-5700 575);
FORCEPROP 1 LAST LOCATION C9M3
J 0
(-5700 875);
DISPLAY 0.617021 (-5700 875);
PAINT AQUA (-5700 875);
FORCEPROP 1 LASTPIN (-5750 675) $PN 2
J 0
(-5740 660);
DISPLAY 0.787234 (-5740 660);
PAINT ORANGE (-5740 660);
DISPLAY INVISIBLE (-5740 660);
FORCEPROP 2 LAST CDS_LIB mstr_discrete
J 0
(-5750 775);
PAINT MONO (-5750 775);
DISPLAY INVISIBLE (-5750 775);
FORCEPROP 2 LAST CDS_SEC 1
J 0
(-5700 975);
PAINT MONO (-5700 975);
DISPLAY INVISIBLE (-5700 975);
FORCEPROP 2 LAST $SEC 1
J 0
(-5700 975);
PAINT MONO (-5700 975);
DISPLAY INVISIBLE (-5700 975);
FORCEPROP 2 LAST CDS_LOCATION C9M3
J 0
(-5700 875);
DISPLAY 0.617021 (-5700 875);
PAINT AQUA (-5700 875);
DISPLAY INVISIBLE (-5700 875);
FORCEPROP 1 LAST PATH I99
J 0
(-5700 925);
DISPLAY 0.978723 (-5700 925);
PAINT ORANGE (-5700 925);
DISPLAY INVISIBLE (-5700 925);
FORCEPROP 1 LASTPIN (-5750 875) $PN 1
J 0
(-5740 860);
DISPLAY 0.787234 (-5740 860);
PAINT ORANGE (-5740 860);
DISPLAY INVISIBLE (-5740 860);
FORCEADD DNS..2
(-6420 4120);
PAINT RED (-6420 4120);
FORCEPROP 1 LAST COMMENT_BODY TRUE
R 1
J 0
(-6345 3895);
DISPLAY 0.872340 (-6345 3895);
PAINT GREEN (-6345 3895);
DISPLAY INVISIBLE (-6345 3895);
FORCEPROP 2 LAST CDS_LIB mstr_misc
J 0
(-6420 4120);
PAINT ORANGE (-6420 4120);
DISPLAY INVISIBLE (-6420 4120);
FORCEADD DNS..2
(-6470 4720);
PAINT RED (-6470 4720);
FORCEPROP 1 LAST COMMENT_BODY TRUE
R 1
J 0
(-6395 4495);
DISPLAY 0.872340 (-6395 4495);
PAINT GREEN (-6395 4495);
DISPLAY INVISIBLE (-6395 4495);
FORCEPROP 2 LAST CDS_LIB mstr_misc
J 0
(-6470 4720);
PAINT ORANGE (-6470 4720);
DISPLAY INVISIBLE (-6470 4720);
FORCEADD DNS..2
(-7345 4120);
PAINT RED (-7345 4120);
FORCEPROP 1 LAST COMMENT_BODY TRUE
R 1
J 0
(-7270 3895);
DISPLAY 0.872340 (-7270 3895);
PAINT GREEN (-7270 3895);
DISPLAY INVISIBLE (-7270 3895);
FORCEPROP 2 LAST CDS_LIB mstr_misc
J 0
(-7345 4120);
PAINT ORANGE (-7345 4120);
DISPLAY INVISIBLE (-7345 4120);
FORCEADD INTEL_CORP_BPAGE..1
(100 100);
FORCEPROP 1 LAST CDS_CON_LAST_MODIFIED Tue Dec 01 11:52:19 2015
J 0
(-1325 425);
DISPLAY 1.361702 (-1325 425);
PAINT GREEN (-1325 425);
DISPLAY INVISIBLE (-1325 425);
FORCEPROP 1 LAST CUSTOM_TXT_CDS <CURRENT_DESIGN_SHEET> OF <TOTAL_DESIGN_SHEETS>
J 0
(-400 125);
PAINT GREEN (-400 125);
FORCEPROP 1 LAST CUSTOM_TXT_CDS <CON_LAST_MODIFIED>
J 0
(-1825 450);
PAINT GREEN (-1825 450);
FORCEPROP 2 LAST CUSTOM_TXT_CDS <XR_PAGE_TITLE>
J 0
(-7790 5350);
DISPLAY 0.638298 (-7790 5350);
PAINT PINK (-7790 5350);
DISPLAY INVISIBLE (-7790 5350);
FORCEPROP 1 LAST SCH_TITLE MOUNTING HOLES + POWER INPUT CONNECTOR
J 0
(-7850 150);
DISPLAY 1.212766 (-7850 150);
PAINT ORANGE (-7850 150);
FORCEPROP 1 LAST SCH_ADDRESS3 Santa Clara, CA 95052-8119
J 0
(-3875 125);
DISPLAY 0.617021 (-3875 125);
PAINT GREEN (-3875 125);
FORCEPROP 1 LAST SCH_ADDRESS2 P.O. BOX 58119
J 0
(-3875 175);
DISPLAY 0.617021 (-3875 175);
PAINT GREEN (-3875 175);
FORCEPROP 1 LAST SCH_ADDRESS1 2200 Mission College Blvd.
J 0
(-3875 225);
DISPLAY 0.617021 (-3875 225);
PAINT GREEN (-3875 225);
FORCEPROP 1 LAST SCH_NUMBER H4694802
J 0
(-1200 250);
DISPLAY 1.212766 (-1200 250);
PAINT YELLOW (-1200 250);
FORCEPROP 1 LAST SCH_DEPT BESD
J 1
(-4350 200);
DISPLAY 1.212766 (-4350 200);
PAINT YELLOW (-4350 200);
FORCEPROP 1 LAST SCH_REV 2.420
J 0
(-150 250);
DISPLAY 0.978723 (-150 250);
PAINT YELLOW (-150 250);
FORCEPROP 2 LAST PAGE_BORDER TRUE
J 0
(-7790 5350);
DISPLAY 0.851064 (-7790 5350);
PAINT PINK (-7790 5350);
DISPLAY INVISIBLE (-7790 5350);
FORCEPROP 1 LAST COMMENT_BODY TRUE
J 0
(112 112);
DISPLAY 0.617021 (112 112);
PAINT GREEN (112 112);
DISPLAY INVISIBLE (112 112);
FORCEPROP 2 LAST CDS_LIB mstr_symbols
J 0
(100 100);
DISPLAY 1.361702 (100 100);
PAINT ORANGE (100 100);
DISPLAY INVISIBLE (100 100);
FORCEPROP 2 LAST CDS_XR_PAGE_TITLE CR-195 : @BASEBOARD_FAB2_LIB.BASEBOARD_FAB2(SCH_1):PAGE195
J 0
(-7790 5350);
DISPLAY 0.638298 (-7790 5350);
PAINT PINK (-7790 5350);
DISPLAY INVISIBLE (-7790 5350);
FORCEADD DNS..2
(-5520 4145);
PAINT RED (-5520 4145);
FORCEPROP 1 LAST COMMENT_BODY TRUE
R 1
J 0
(-5445 3920);
DISPLAY 0.872340 (-5445 3920);
PAINT GREEN (-5445 3920);
DISPLAY INVISIBLE (-5445 3920);
FORCEPROP 2 LAST CDS_LIB mstr_misc
J 0
(-5520 4145);
PAINT ORANGE (-5520 4145);
DISPLAY INVISIBLE (-5520 4145);
FORCEADD DNS..2
(-5520 4720);
PAINT RED (-5520 4720);
FORCEPROP 1 LAST COMMENT_BODY TRUE
R 1
J 0
(-5445 4495);
DISPLAY 0.872340 (-5445 4495);
PAINT GREEN (-5445 4495);
DISPLAY INVISIBLE (-5445 4495);
FORCEPROP 2 LAST CDS_LIB mstr_misc
J 0
(-5520 4720);
PAINT ORANGE (-5520 4720);
DISPLAY INVISIBLE (-5520 4720);
FORCEADD DNS..2
(-4595 4145);
PAINT RED (-4595 4145);
FORCEPROP 1 LAST COMMENT_BODY TRUE
R 1
J 0
(-4520 3920);
DISPLAY 0.872340 (-4520 3920);
PAINT GREEN (-4520 3920);
DISPLAY INVISIBLE (-4520 3920);
FORCEPROP 2 LAST CDS_LIB mstr_misc
J 0
(-4595 4145);
PAINT ORANGE (-4595 4145);
DISPLAY INVISIBLE (-4595 4145);
FORCEADD DNS..2
(-4595 4720);
PAINT RED (-4595 4720);
FORCEPROP 1 LAST COMMENT_BODY TRUE
R 1
J 0
(-4520 4495);
DISPLAY 0.872340 (-4520 4495);
PAINT GREEN (-4520 4495);
DISPLAY INVISIBLE (-4520 4495);
FORCEPROP 2 LAST CDS_LIB mstr_misc
J 0
(-4595 4720);
PAINT ORANGE (-4595 4720);
DISPLAY INVISIBLE (-4595 4720);
WIRE 16 -1 (-4850 2050)(-4850 2225);
WIRE 16 -1 (-4850 2225)(-5275 2225);
WIRE 16 -1 (-5275 2225)(-5725 2225);
WIRE 16 -1 (-5275 2225)(-5275 2025);
WIRE 16 -1 (-5725 2050)(-5725 2225);
WIRE 16 -1 (-5725 2225)(-6150 2225);
WIRE 16 -1 (-6150 2050)(-6150 2225);
WIRE 16 -1 (-6150 2225)(-6375 2225);
WIRE 16 -1 (-6525 2225)(-6375 2225);
WIRE 16 -1 (-6375 2225)(-6375 2275);
WIRE 16 -1 (-6525 2225)(-6875 2225);
WIRE 16 -1 (-6525 2050)(-6525 2225);
WIRE 16 -1 (-6875 2225)(-7250 2225);
WIRE 16 -1 (-6875 2050)(-6875 2225);
WIRE 16 -1 (-7675 2225)(-7250 2225);
WIRE 16 -1 (-7250 2050)(-7250 2225);
WIRE 16 -1 (-7675 2225)(-7675 2050);
WIRE 16 -1 (-4850 1850)(-4850 1650);
WIRE 16 -1 (-4850 1650)(-5275 1650);
WIRE 16 -1 (-5275 1825)(-5275 1650);
WIRE 16 -1 (-5275 1650)(-5725 1650);
WIRE 16 -1 (-5725 1850)(-5725 1650);
WIRE 16 -1 (-5725 1650)(-6150 1650);
WIRE 16 -1 (-6150 1850)(-6150 1650);
WIRE 16 -1 (-6150 1650)(-6375 1650);
WIRE 16 -1 (-6525 1650)(-6375 1650);
WIRE 16 -1 (-6375 1650)(-6375 1550);
WIRE 16 -1 (-6525 1650)(-6875 1650);
WIRE 16 -1 (-6525 1850)(-6525 1650);
WIRE 16 -1 (-6875 1650)(-7250 1650);
WIRE 16 -1 (-6875 1850)(-6875 1650);
WIRE 16 -1 (-7675 1650)(-7250 1650);
WIRE 16 -1 (-7250 1850)(-7250 1650);
WIRE 16 -1 (-7675 1850)(-7675 1650);
WIRE 16 -1 (-3700 2250)(-3275 2250);
WIRE 16 -1 (-3700 2300)(-3700 2250);
WIRE 16 -1 (-3700 2300)(-3275 2300);
WIRE 16 -1 (-3700 2350)(-3700 2300);
WIRE 16 -1 (-3275 2350)(-3700 2350);
WIRE 16 -1 (-3700 2350)(-3700 2700);
WIRE 16 -1 (-725 3775)(-475 3775);
WIRE 16 -1 (-475 3775)(-475 3675);
WIRE 16 -1 (-725 3675)(-475 3675);
WIRE 16 -1 (-475 3675)(-475 3575);
WIRE 16 -1 (-725 3575)(-475 3575);
WIRE 16 -1 (-475 3575)(-475 3425);
WIRE 16 -1 (-3275 2150)(-3550 2150);
WIRE 16 -1 (-3550 2150)(-3550 2100);
WIRE 16 -1 (-3550 2100)(-3275 2100);
WIRE 16 -1 (-3550 2100)(-3550 2050);
WIRE 16 -1 (-3550 2050)(-3275 2050);
WIRE 16 -1 (-3550 2050)(-3550 1950);
WIRE 16 -1 (-1625 3575)(-1625 3525);
WIRE 16 -1 (-1625 3525)(-1950 3525);
WIRE 16 -1 (-1950 3575)(-1950 3525);
WIRE 16 -1 (-1950 3525)(-2300 3525);
WIRE 16 -1 (-2300 3575)(-2300 3525);
WIRE 16 -1 (-2300 3525)(-2675 3525);
WIRE 16 -1 (-2675 3575)(-2675 3525);
WIRE 16 -1 (-2675 3525)(-3025 3525);
WIRE 16 -1 (-3025 3525)(-3025 3575);
WIRE 16 -1 (-3375 3525)(-3025 3525);
WIRE 16 -1 (-3375 3525)(-3375 3575);
WIRE 16 -1 (-3700 3525)(-3375 3525);
WIRE 16 -1 (-3700 3575)(-3700 3525);
WIRE 16 -1 (-3700 3475)(-3700 3525);
WIRE 16 -1 (-2775 2150)(-2450 2150);
WIRE 16 -1 (-2450 2150)(-2450 2100);
WIRE 16 -1 (-2450 2100)(-2450 2050);
WIRE 16 -1 (-2450 2100)(-2775 2100);
WIRE 16 -1 (-2450 2050)(-2775 2050);
WIRE 16 -1 (-2450 2050)(-2450 1950);
WIRE 16 -1 (-2775 2250)(-2325 2250);
WIRE 16 -1 (-2325 2250)(-2325 2300);
WIRE 16 -1 (-2775 2300)(-2325 2300);
WIRE 16 -1 (-2325 2300)(-2325 2350);
WIRE 16 -1 (-2775 2350)(-2325 2350);
WIRE 16 -1 (-2325 2350)(-2325 2700);
WIRE 16 -1 (-3700 3775)(-3700 3825);
WIRE 16 -1 (-3700 3825)(-3375 3825);
WIRE 16 -1 (-3375 3825)(-3025 3825);
WIRE 16 -1 (-3375 3825)(-3375 3775);
WIRE 16 -1 (-3025 3825)(-2675 3825);
WIRE 16 -1 (-3025 3825)(-3025 3775);
WIRE 16 -1 (-2300 3825)(-2675 3825);
WIRE 16 -1 (-2675 3825)(-2675 3775);
WIRE 16 -1 (-2300 3775)(-2300 3825);
WIRE 16 -1 (-1950 3825)(-2300 3825);
WIRE 16 -1 (-1950 3775)(-1950 3825);
WIRE 16 -1 (-1625 3825)(-1950 3825);
WIRE 16 -1 (-1625 3775)(-1625 3825);
WIRE 16 -1 (-1625 3825)(-1625 3975);
WIRE 16 -1 (-6725 4725)(-6900 4725);
WIRE 16 -1 (-6900 4725)(-6900 4575);
WIRE 16 -1 (-6675 4125)(-6850 4125);
WIRE 16 -1 (-6850 4125)(-6850 3975);
WIRE 16 -1 (-4850 4725)(-5025 4725);
WIRE 16 -1 (-5025 4725)(-5025 4575);
WIRE 16 -1 (-5775 4725)(-5950 4725);
WIRE 16 -1 (-5950 4725)(-5950 4575);
WIRE 16 -1 (-7600 4125)(-7775 4125);
WIRE 16 -1 (-7775 4125)(-7775 3975);
WIRE 16 -1 (-5775 4150)(-5950 4150);
WIRE 16 -1 (-5950 4150)(-5950 4000);
WIRE 16 -1 (-4850 4150)(-5025 4150);
WIRE 16 -1 (-5025 4150)(-5025 4000);
WIRE 16 -1 (-1000 2275)(-550 2275);
WIRE 16 -1 (-550 2275)(-550 2325);
WIRE 16 -1 (-1000 2325)(-550 2325);
WIRE 16 -1 (-550 2325)(-550 2375);
WIRE 16 -1 (-1000 2375)(-550 2375);
WIRE 16 -1 (-550 2375)(-550 2725);
WIRE 16 -1 (-1000 2175)(-675 2175);
WIRE 16 -1 (-675 2175)(-675 2125);
WIRE 16 -1 (-675 2125)(-675 2075);
WIRE 16 -1 (-675 2125)(-1000 2125);
WIRE 16 -1 (-675 2075)(-1000 2075);
WIRE 16 -1 (-675 2075)(-675 1975);
WIRE 16 -1 (-1925 2275)(-1500 2275);
WIRE 16 -1 (-1925 2325)(-1925 2275);
WIRE 16 -1 (-1925 2325)(-1500 2325);
WIRE 16 -1 (-1925 2375)(-1925 2325);
WIRE 16 -1 (-1500 2375)(-1925 2375);
WIRE 16 -1 (-1925 2375)(-1925 2725);
WIRE 16 -1 (-1500 2175)(-1775 2175);
WIRE 16 -1 (-1775 2175)(-1775 2125);
WIRE 16 -1 (-1775 2125)(-1500 2125);
WIRE 16 -1 (-1775 2125)(-1775 2075);
WIRE 16 -1 (-1775 2075)(-1500 2075);
WIRE 16 -1 (-1775 2075)(-1775 1975);
WIRE 16 -1 (-5650 3000)(-5650 3200);
WIRE 16 -1 (-5650 3200)(-6150 3200);
WIRE 16 -1 (-6150 3025)(-6150 3200);
WIRE 16 -1 (-6150 3200)(-6250 3200);
WIRE 16 -1 (-6675 3200)(-6250 3200);
WIRE 16 -1 (-6250 3200)(-6250 3325);
WIRE 16 -1 (-7175 3200)(-6675 3200);
WIRE 16 -1 (-6675 3050)(-6675 3200);
WIRE 16 -1 (-7175 3050)(-7175 3200);
WIRE 16 -1 (-4875 875)(-4875 1050);
WIRE 16 -1 (-4875 1050)(-5300 1050);
WIRE 16 -1 (-5300 1050)(-5750 1050);
WIRE 16 -1 (-5300 1050)(-5300 850);
WIRE 16 -1 (-5750 875)(-5750 1050);
WIRE 16 -1 (-5750 1050)(-6175 1050);
WIRE 16 -1 (-6175 875)(-6175 1050);
WIRE 16 -1 (-6175 1050)(-6400 1050);
WIRE 16 -1 (-6550 1050)(-6400 1050);
WIRE 16 -1 (-6400 1050)(-6400 1100);
WIRE 16 -1 (-6550 1050)(-6900 1050);
WIRE 16 -1 (-6550 875)(-6550 1050);
WIRE 16 -1 (-6900 1050)(-7275 1050);
WIRE 16 -1 (-6900 875)(-6900 1050);
WIRE 16 -1 (-7700 1050)(-7275 1050);
WIRE 16 -1 (-7275 875)(-7275 1050);
WIRE 16 -1 (-7700 1050)(-7700 875);
WIRE 16 -1 (-4875 675)(-4875 475);
WIRE 16 -1 (-4875 475)(-5300 475);
WIRE 16 -1 (-5300 650)(-5300 475);
WIRE 16 -1 (-5300 475)(-5750 475);
WIRE 16 -1 (-5750 675)(-5750 475);
WIRE 16 -1 (-5750 475)(-6175 475);
WIRE 16 -1 (-6175 675)(-6175 475);
WIRE 16 -1 (-6175 475)(-6400 475);
WIRE 16 -1 (-6550 475)(-6400 475);
WIRE 16 -1 (-6400 475)(-6400 375);
WIRE 16 -1 (-6550 475)(-6900 475);
WIRE 16 -1 (-6550 675)(-6550 475);
WIRE 16 -1 (-6900 475)(-7275 475);
WIRE 16 -1 (-6900 675)(-6900 475);
WIRE 16 -1 (-7700 475)(-7275 475);
WIRE 16 -1 (-7275 675)(-7275 475);
WIRE 16 -1 (-7700 675)(-7700 475);
WIRE 16 -1 (-5650 2800)(-5650 2625);
WIRE 16 -1 (-5650 2625)(-6150 2625);
WIRE 16 -1 (-6150 2825)(-6150 2625);
WIRE 16 -1 (-6375 2625)(-6150 2625);
WIRE 16 -1 (-6675 2625)(-6375 2625);
WIRE 16 -1 (-6375 2625)(-6375 2600);
WIRE 16 -1 (-7175 2625)(-6675 2625);
WIRE 16 -1 (-6675 2850)(-6675 2625);
WIRE 16 -1 (-7175 2850)(-7175 2625);
WIRE 16 682 (-4225 4975)(-4225 550);
WIRE 16 -1 (-4225 550)(-4200 550);
DOT 1 (-7275 475);
DOT 1 (-7275 1050);
DOT 1 (-7250 1650);
DOT 1 (-6900 475);
DOT 1 (-6550 475);
DOT 1 (-6400 475);
DOT 1 (-6175 475);
DOT 1 (-6900 1050);
DOT 1 (-6875 1650);
DOT 1 (-6400 1050);
DOT 1 (-6550 1050);
DOT 1 (-6175 1050);
DOT 1 (-6525 1650);
DOT 1 (-6375 1650);
DOT 1 (-6150 1650);
DOT 1 (-7250 2225);
DOT 1 (-6875 2225);
DOT 1 (-6675 2625);
DOT 1 (-6525 2225);
DOT 1 (-6375 2225);
DOT 1 (-6150 2225);
DOT 1 (-6375 2625);
DOT 1 (-6150 2625);
DOT 1 (-6675 3200);
DOT 1 (-6250 3200);
DOT 1 (-6150 3200);
DOT 1 (-5750 475);
DOT 1 (-5300 475);
DOT 1 (-5750 1050);
DOT 1 (-5725 1650);
DOT 1 (-5300 1050);
DOT 1 (-5275 1650);
DOT 1 (-5725 2225);
DOT 1 (-5275 2225);
DOT 1 (-3550 2050);
DOT 1 (-2450 2050);
DOT 1 (-3700 2300);
DOT 1 (-3700 2350);
DOT 1 (-3550 2100);
DOT 1 (-3700 3525);
DOT 1 (-3375 3525);
DOT 1 (-3375 3825);
DOT 1 (-2450 2100);
DOT 1 (-2325 2300);
DOT 1 (-2325 2350);
DOT 1 (-3025 3525);
DOT 1 (-2675 3525);
DOT 1 (-3025 3825);
DOT 1 (-2675 3825);
DOT 1 (-2300 3525);
DOT 1 (-2300 3825);
DOT 1 (-1925 2375);
DOT 1 (-1925 2325);
DOT 1 (-1775 2075);
DOT 1 (-1775 2125);
DOT 1 (-1950 3525);
DOT 1 (-1950 3825);
DOT 1 (-1625 3825);
DOT 1 (-675 2075);
DOT 1 (-675 2125);
DOT 1 (-550 2325);
DOT 1 (-550 2375);
DOT 1 (-475 3575);
DOT 1 (-475 3675);
FORCENOTE
BOM_COST=TEST_MFG
(-6625 3700) 0;
DISPLAY LEFT (-6625 3700);
DISPLAY 1.021277 (-6625 3700);
PAINT PURPLE (-6625 3700);
FORCENOTE
BULK CAPS TO SUPPORT FAST PROCHOT
(-7175 3525) 0;
DISPLAY LEFT (-7175 3525);
DISPLAY 1.595745 (-7175 3525);
PAINT PURPLE (-7175 3525);
FORCENOTE
ROOM=MOUNTING_HOLES
(-6625 3775) 0;
DISPLAY LEFT (-6625 3775);
DISPLAY 1.021277 (-6625 3775);
PAINT PURPLE (-6625 3775);
FORCENOTE
ROOM: HOT_SWAP
(-3295 1675) 0;
DISPLAY LEFT (-3295 1675);
DISPLAY 1.021277 (-3295 1675);
PAINT PURPLE (-3295 1675);
FORCENOTE
POWER CONN: 40AMAX
(-3325 1775) 0;
DISPLAY LEFT (-3325 1775);
DISPLAY 1.595745 (-3325 1775);
PAINT PURPLE (-3325 1775);
FORCENOTE
ROOM: HOT_SWAP
(-1520 1700) 0;
DISPLAY LEFT (-1520 1700);
DISPLAY 1.021277 (-1520 1700);
PAINT PURPLE (-1520 1700);
FORCENOTE
POWER CONN: 40A MAX
(-1550 1800) 0;
DISPLAY LEFT (-1550 1800);
DISPLAY 1.595745 (-1550 1800);
PAINT PURPLE (-1550 1800);
FORCENOTE
GUIDE PIN
(-1200 3325) 0;
DISPLAY LEFT (-1200 3325);
DISPLAY 1.595745 (-1200 3325);
PAINT PURPLE (-1200 3325);
QUIT
